FILE_TYPE = MACRO_DRAWING;
SET COLOR_WIRE YELLOW;
SET COLOR_PROP ORANGE;
SET COLOR_DOT WHITE;
SET COLOR_ARC YELLOW;
SET COLOR_BODY GREEN;
SET COLOR_NOTE PURPLE;
SET PROP_DISPLAY VALUE;
SET PAGE_NUMBER P221;
FORCEADD UNIVERSAL_GND..1
(-3150 -150);
FORCEPROP 3 LASTPIN (-3150 -100) SIG_NAME GND\g
J 0
(-3140 -90);
DISPLAY 0.659574 (-3140 -90);
PAINT MONO (-3140 -90);
DISPLAY INVISIBLE (-3140 -90);
FORCEPROP 2 LAST CDS_LIB logical_power
J 0
(-3150 -150);
PAINT MONO (-3150 -150);
DISPLAY INVISIBLE (-3150 -150);
FORCEPROP 2 LAST ROOM IO_SLOT
J 1
(-3375 -75);
DISPLAY 0.744681 (-3375 -75);
DISPLAY INVISIBLE (-3375 -75);
FORCEPROP 1 LAST HDL_POWER GND
J 1
(-3125 -225);
DISPLAY 0.872340 (-3125 -225);
PAINT GREEN (-3125 -225);
DISPLAY INVISIBLE (-3125 -225);
FORCEPROP 1 LAST PATH I1
J 0
(-3075 -150);
DISPLAY 0.872340 (-3075 -150);
PAINT AQUA (-3075 -150);
DISPLAY INVISIBLE (-3075 -150);
FORCEADD Q_RES..2
(-2600 725);
FORCEPROP 1 LAST PART_NUMBER CS31002FB08
J 0
(-2560 600);
DISPLAY 0.510638 (-2560 600);
DISPLAY INVISIBLE (-2560 600);
FORCEPROP 1 LAST PACK_TYPE 0402LF
J 0
(-2560 550);
DISPLAY 0.638298 (-2560 550);
FORCEPROP 1 LAST MATERIAL EMPTY
J 0
(-2560 650);
DISPLAY 0.638298 (-2560 650);
PAINT RED (-2560 650);
FORCEPROP 1 LAST TOLERANCE 1%
J 0
(-2555 750);
DISPLAY 0.638298 (-2555 750);
FORCEPROP 1 LAST VALUE 10K
J 0
(-2555 800);
DISPLAY 0.638298 (-2555 800);
FORCEPROP 1 LAST WATTAGE 1/16W
J 0
(-2560 700);
DISPLAY 0.638298 (-2560 700);
FORCEPROP 1 LAST $LOCATION R3708
J 0
(-2555 850);
DISPLAY 0.978723 (-2555 850);
FORCEPROP 1 LASTPIN (-2600 825) $PN 1
J 0
(-2595 787);
DISPLAY 0.787234 (-2595 787);
FORCEPROP 1 LASTPIN (-2600 625) $PN 2
J 0
(-2595 635);
DISPLAY 0.787234 (-2595 635);
FORCEPROP 2 LAST CDS_LIB pure_quanta
J 0
(-2600 725);
PAINT MONO (-2600 725);
DISPLAY INVISIBLE (-2600 725);
FORCEPROP 1 LAST PATH I10
J 0
(-2550 900);
DISPLAY 0.978723 (-2550 900);
PAINT WHITE (-2550 900);
DISPLAY INVISIBLE (-2550 900);
FORCEPROP 2 LAST CDS_LOCATION R3708
J 0
(-2550 950);
DISPLAY 1.021277 (-2550 950);
DISPLAY INVISIBLE (-2550 950);
FORCEPROP 2 LAST $SEC 1
J 0
(-2550 950);
DISPLAY 0.680851 (-2550 950);
PAINT MONO (-2550 950);
DISPLAY INVISIBLE (-2550 950);
FORCEPROP 2 LAST CDS_SEC 1
J 0
(-2550 950);
DISPLAY 1.021277 (-2550 950);
DISPLAY INVISIBLE (-2550 950);
FORCEADD OFFPAGE..2
(3350 -425);
FORCEPROP 2 LAST $XR1 240 
J 0
(3659 -425);
DISPLAY 0.638298 (3659 -425);
PAINT MONO (3659 -425);
FORCEPROP 2 LAST $XR0 233 
J 0
(3539 -425);
DISPLAY 0.638298 (3539 -425);
PAINT MONO (3539 -425);
FORCEPROP 2 LAST CDS_LIB standard
J 0
(3350 -425);
PAINT MONO (3350 -425);
DISPLAY INVISIBLE (3350 -425);
FORCEPROP 1 LAST OFFPAGE TRUE
J 0
(3675 -550);
DISPLAY 0.872340 (3675 -550);
PAINT GREEN (3675 -550);
DISPLAY INVISIBLE (3675 -550);
FORCEPROP 1 LAST COMMENT_BODY TRUE
J 0
(3305 -520);
DISPLAY 0.872340 (3305 -520);
PAINT GREEN (3305 -520);
DISPLAY INVISIBLE (3305 -520);
FORCEPROP 2 LAST PATH I100
J 0
(3675 -375);
DISPLAY 1.021277 (3675 -375);
DISPLAY INVISIBLE (3675 -375);
FORCEADD OFFPAGE..2
(3350 -475);
FORCEPROP 2 LAST $XR1 233 
J 0
(3659 -475);
DISPLAY 0.638298 (3659 -475);
PAINT MONO (3659 -475);
FORCEPROP 2 LAST $XR0 240 
J 0
(3539 -475);
DISPLAY 0.638298 (3539 -475);
PAINT MONO (3539 -475);
FORCEPROP 2 LAST CDS_LIB standard
J 0
(3350 -475);
PAINT MONO (3350 -475);
DISPLAY INVISIBLE (3350 -475);
FORCEPROP 1 LAST OFFPAGE TRUE
J 0
(3675 -600);
DISPLAY 0.872340 (3675 -600);
PAINT GREEN (3675 -600);
DISPLAY INVISIBLE (3675 -600);
FORCEPROP 1 LAST COMMENT_BODY TRUE
J 0
(3305 -570);
DISPLAY 0.872340 (3305 -570);
PAINT GREEN (3305 -570);
DISPLAY INVISIBLE (3305 -570);
FORCEPROP 2 LAST PATH I101
J 0
(3675 -425);
DISPLAY 1.021277 (3675 -425);
DISPLAY INVISIBLE (3675 -425);
FORCEADD Q_RES..1
(1975 -425);
FORCEPROP 1 LAST PART_NUMBER CS22202JB07
J 0
(1825 -350);
DISPLAY 0.510638 (1825 -350);
DISPLAY INVISIBLE (1825 -350);
FORCEPROP 1 LAST WATTAGE 1/16W
J 2
(2125 -300);
DISPLAY 0.510638 (2125 -300);
FORCEPROP 1 LAST PACK_TYPE 0402LF
J 0
(1825 -300);
DISPLAY 0.510638 (1825 -300);
FORCEPROP 1 LAST MATERIAL EMPTY
J 0
(2350 -425);
DISPLAY 0.638298 (2350 -425);
PAINT RED (2350 -425);
FORCEPROP 1 LAST VALUE 2.2K
J 2
(2250 -425);
DISPLAY 0.638298 (2250 -425);
FORCEPROP 1 LAST TOLERANCE 5%
J 0
(2250 -425);
DISPLAY 0.638298 (2250 -425);
FORCEPROP 1 LAST $LOCATION R4269
J 0
(1725 -425);
DISPLAY 0.510638 (1725 -425);
FORCEPROP 2 LAST CDS_LIB pure_quanta
J 0
(1975 -425);
DISPLAY INVISIBLE (1975 -425);
FORCEPROP 1 LAST PATH I102
J 0
(1925 -275);
DISPLAY 0.978723 (1925 -275);
PAINT WHITE (1925 -275);
DISPLAY INVISIBLE (1925 -275);
FORCEPROP 0 LAST CDS_LOCATION R4269
J 0
(2125 -275);
DISPLAY INVISIBLE (2125 -275);
FORCEPROP 0 LAST $SEC 1
J 0
(2125 -275);
DISPLAY INVISIBLE (2125 -275);
FORCEPROP 0 LAST CDS_SEC 1
J 0
(2125 -275);
DISPLAY INVISIBLE (2125 -275);
FORCEPROP 1 LASTPIN (1875 -425) $PN 1
J 0
(1887 -413);
DISPLAY 0.787234 (1887 -413);
PAINT MONO (1887 -413);
DISPLAY INVISIBLE (1887 -413);
FORCEPROP 1 LASTPIN (2075 -425) $PN 2
J 0
(2037 -413);
DISPLAY 0.787234 (2037 -413);
PAINT MONO (2037 -413);
DISPLAY INVISIBLE (2037 -413);
FORCEADD TCA9548APWR..1
(250 2525);
FORCEPROP 1 LAST PART_NUMBER AL009548K02
J 0
(50 3052);
DISPLAY 0.723404 (50 3052);
PAINT GREEN (50 3052);
DISPLAY INVISIBLE (50 3052);
FORCEPROP 2 LAST PART_TYPE SMLF
J 0
(50 3200);
DISPLAY 1.021277 (50 3200);
FORCEPROP 1 LAST MATERIAL IC
J 0
(50 3005);
DISPLAY 0.723404 (50 3005);
PAINT GREEN (50 3005);
FORCEPROP 2 LAST VALUE TCA9548APWR
J 0
(50 3150);
DISPLAY 1.021277 (50 3150);
FORCEPROP 1 LAST LOCATION U39
J 0
(50 3105);
DISPLAY 0.723404 (50 3105);
PAINT GREEN (50 3105);
FORCEPROP 2 LASTPIN (-100 2850) $PN 1
J 2
(-110 2860);
DISPLAY 0.680851 (-110 2860);
PAINT MONO (-110 2860);
FORCEPROP 2 LASTPIN (-100 2800) $PN 2
J 2
(-110 2810);
DISPLAY 0.680851 (-110 2810);
PAINT MONO (-110 2810);
FORCEPROP 2 LASTPIN (-100 2750) $PN 21
J 2
(-110 2760);
DISPLAY 0.680851 (-110 2760);
PAINT MONO (-110 2760);
FORCEPROP 2 LASTPIN (600 2100) $PN 12
J 0
(610 2110);
DISPLAY 0.680851 (610 2110);
PAINT MONO (610 2110);
FORCEPROP 2 LASTPIN (-100 2650) $PN 3
J 2
(-110 2660);
DISPLAY 0.680851 (-110 2660);
PAINT MONO (-110 2660);
FORCEPROP 2 LASTPIN (-100 2500) $PN 5
J 2
(-110 2510);
DISPLAY 0.680851 (-110 2510);
PAINT MONO (-110 2510);
FORCEPROP 2 LASTPIN (-100 2400) $PN 7
J 2
(-110 2410);
DISPLAY 0.680851 (-110 2410);
PAINT MONO (-110 2410);
FORCEPROP 2 LASTPIN (-100 2300) $PN 9
J 2
(-110 2310);
DISPLAY 0.680851 (-110 2310);
PAINT MONO (-110 2310);
FORCEPROP 2 LASTPIN (-100 2200) $PN 11
J 2
(-110 2210);
DISPLAY 0.680851 (-110 2210);
PAINT MONO (-110 2210);
FORCEPROP 2 LASTPIN (600 2500) $PN 14
J 0
(610 2510);
DISPLAY 0.680851 (610 2510);
PAINT MONO (610 2510);
FORCEPROP 2 LASTPIN (600 2400) $PN 16
J 0
(610 2410);
DISPLAY 0.680851 (610 2410);
PAINT MONO (610 2410);
FORCEPROP 2 LASTPIN (600 2300) $PN 18
J 0
(610 2310);
DISPLAY 0.680851 (610 2310);
PAINT MONO (610 2310);
FORCEPROP 2 LASTPIN (600 2200) $PN 20
J 0
(610 2210);
DISPLAY 0.680851 (610 2210);
PAINT MONO (610 2210);
FORCEPROP 2 LASTPIN (600 2750) $PN 22
J 0
(610 2760);
DISPLAY 0.680851 (610 2760);
PAINT MONO (610 2760);
FORCEPROP 2 LASTPIN (-100 2550) $PN 4
J 2
(-110 2560);
DISPLAY 0.680851 (-110 2560);
PAINT MONO (-110 2560);
FORCEPROP 2 LASTPIN (-100 2450) $PN 6
J 2
(-110 2460);
DISPLAY 0.680851 (-110 2460);
PAINT MONO (-110 2460);
FORCEPROP 2 LASTPIN (-100 2350) $PN 8
J 2
(-110 2360);
DISPLAY 0.680851 (-110 2360);
PAINT MONO (-110 2360);
FORCEPROP 2 LASTPIN (-100 2250) $PN 10
J 2
(-110 2260);
DISPLAY 0.680851 (-110 2260);
PAINT MONO (-110 2260);
FORCEPROP 2 LASTPIN (600 2550) $PN 13
J 0
(610 2560);
DISPLAY 0.680851 (610 2560);
PAINT MONO (610 2560);
FORCEPROP 2 LASTPIN (600 2450) $PN 15
J 0
(610 2460);
DISPLAY 0.680851 (610 2460);
PAINT MONO (610 2460);
FORCEPROP 2 LASTPIN (600 2350) $PN 17
J 0
(610 2360);
DISPLAY 0.680851 (610 2360);
PAINT MONO (610 2360);
FORCEPROP 2 LASTPIN (600 2250) $PN 19
J 0
(610 2260);
DISPLAY 0.680851 (610 2260);
PAINT MONO (610 2260);
FORCEPROP 2 LASTPIN (600 2800) $PN 23
J 0
(610 2810);
DISPLAY 0.680851 (610 2810);
PAINT MONO (610 2810);
FORCEPROP 2 LASTPIN (-100 2950) $PN 24
J 2
(-110 2960);
DISPLAY 0.680851 (-110 2960);
PAINT MONO (-110 2960);
FORCEPROP 2 LAST CDS_LIB pure_quanta
J 0
(250 2525);
DISPLAY INVISIBLE (250 2525);
FORCEPROP 1 LAST CDS_LMAN_SYM_OUTLINE -200,475,200,-475
J 0
(250 2525);
DISPLAY 0.468085 (250 2525);
PAINT GREEN (250 2525);
DISPLAY INVISIBLE (250 2525);
FORCEPROP 1 LAST NEEDS_NO_SIZE TRUE
J 0
(250 2525);
DISPLAY 0.723404 (250 2525);
PAINT GREEN (250 2525);
DISPLAY INVISIBLE (250 2525);
FORCEPROP 2 LAST SEC_TYPE 
J 0
(50 3250);
DISPLAY 1.021277 (50 3250);
DISPLAY INVISIBLE (50 3250);
FORCEPROP 1 LAST PATH I103
J 0
(250 2525);
DISPLAY 0.723404 (250 2525);
PAINT GREEN (250 2525);
DISPLAY INVISIBLE (250 2525);
FORCEPROP 2 LAST SEC 1
J 0
(50 3250);
DISPLAY 0.680851 (50 3250);
PAINT MONO (50 3250);
DISPLAY INVISIBLE (50 3250);
FORCEADD UNIVERSAL_POWER..1
(-625 3600);
FORCEPROP 3 LASTPIN (-625 3550) SIG_NAME P3V3_AUX\g
J 0
(-615 3560);
DISPLAY 0.659574 (-615 3560);
PAINT MONO (-615 3560);
DISPLAY INVISIBLE (-615 3560);
FORCEPROP 1 LAST HDL_POWER P3V3_AUX
J 1
(-625 3650);
DISPLAY 0.872340 (-625 3650);
PAINT GREEN (-625 3650);
FORCEPROP 2 LAST CDS_LIB logical_power
J 0
(-625 3600);
PAINT MONO (-625 3600);
DISPLAY INVISIBLE (-625 3600);
FORCEPROP 1 LAST PATH I104
J 0
(-575 3625);
DISPLAY 0.872340 (-575 3625);
PAINT AQUA (-575 3625);
DISPLAY INVISIBLE (-575 3625);
FORCEADD UNIVERSAL_GND..1
(-625 3050);
FORCEPROP 3 LASTPIN (-625 3100) SIG_NAME GND\g
J 0
(-615 3110);
DISPLAY 0.659574 (-615 3110);
PAINT MONO (-615 3110);
DISPLAY INVISIBLE (-615 3110);
FORCEPROP 2 LAST CDS_LIB logical_power
J 0
(-625 3050);
PAINT MONO (-625 3050);
DISPLAY INVISIBLE (-625 3050);
FORCEPROP 1 LAST HDL_POWER GND
J 1
(-600 2975);
DISPLAY 0.872340 (-600 2975);
PAINT GREEN (-600 2975);
DISPLAY INVISIBLE (-600 2975);
FORCEPROP 1 LAST PATH I105
J 0
(-550 3050);
DISPLAY 0.872340 (-550 3050);
PAINT AQUA (-550 3050);
DISPLAY INVISIBLE (-550 3050);
FORCEADD Q_CAP..1
(-625 3275);
FORCEPROP 1 LAST PART_NUMBER CH4104K1B00
J 0
(-575 3125);
DISPLAY 0.510638 (-575 3125);
DISPLAY INVISIBLE (-575 3125);
FORCEPROP 1 LAST VOLTAGE 25V
J 0
(-575 3275);
DISPLAY 0.510638 (-575 3275);
FORCEPROP 1 LAST VALUE 0.1UF
J 0
(-575 3325);
DISPLAY 0.510638 (-575 3325);
FORCEPROP 1 LAST TOLERANCE 10%
J 0
(-575 3225);
DISPLAY 0.510638 (-575 3225);
FORCEPROP 1 LAST MATERIAL X7R
J 0
(-575 3175);
DISPLAY 0.510638 (-575 3175);
FORCEPROP 1 LAST PACK_TYPE 0402
J 0
(-575 3075);
DISPLAY 0.510638 (-575 3075);
FORCEPROP 1 LAST $LOCATION C2056
J 0
(-575 3375);
DISPLAY 0.978723 (-575 3375);
FORCEPROP 1 LASTPIN (-625 3375) $PN 1
J 0
(-615 3355);
DISPLAY 0.787234 (-615 3355);
FORCEPROP 1 LASTPIN (-625 3175) $PN 2
J 0
(-615 3155);
DISPLAY 0.787234 (-615 3155);
FORCEPROP 2 LAST CDS_LIB pure_quanta
J 2
(-625 3275);
PAINT MONO (-625 3275);
DISPLAY INVISIBLE (-625 3275);
FORCEPROP 1 LAST PATH I106
J 0
(-575 3425);
DISPLAY 0.978723 (-575 3425);
PAINT WHITE (-575 3425);
DISPLAY INVISIBLE (-575 3425);
FORCEPROP 2 LAST CDS_LOCATION C2056
J 2
(-575 3475);
DISPLAY 1.021277 (-575 3475);
DISPLAY INVISIBLE (-575 3475);
FORCEPROP 2 LAST $SEC 1
J 0
(-575 3475);
DISPLAY 0.680851 (-575 3475);
PAINT MONO (-575 3475);
DISPLAY INVISIBLE (-575 3475);
FORCEPROP 2 LAST CDS_SEC 1
J 0
(-575 3475);
DISPLAY 1.021277 (-575 3475);
DISPLAY INVISIBLE (-575 3475);
FORCEADD OFFPAGE..1
(-825 2850);
FORCEPROP 2 LAST $XR0 233 
J 0
(-1077 2850);
DISPLAY 0.638298 (-1077 2850);
PAINT MONO (-1077 2850);
FORCEPROP 2 LAST CDS_LIB standard
J 0
(-825 2850);
DISPLAY INVISIBLE (-825 2850);
FORCEPROP 1 LAST OFFPAGE TRUE
J 0
(-500 2725);
DISPLAY 0.872340 (-500 2725);
PAINT GREEN (-500 2725);
DISPLAY INVISIBLE (-500 2725);
FORCEPROP 1 LAST COMMENT_BODY TRUE
J 0
(-700 2750);
DISPLAY 0.872340 (-700 2750);
PAINT GREEN (-700 2750);
DISPLAY INVISIBLE (-700 2750);
FORCEPROP 2 LAST PATH I107
J 0
(-1075 2900);
DISPLAY 1.021277 (-1075 2900);
DISPLAY INVISIBLE (-1075 2900);
FORCEADD OFFPAGE..1
(-825 2800);
FORCEPROP 2 LAST $XR0 233 
J 0
(-1077 2800);
DISPLAY 0.638298 (-1077 2800);
PAINT MONO (-1077 2800);
FORCEPROP 2 LAST CDS_LIB standard
J 0
(-825 2800);
DISPLAY INVISIBLE (-825 2800);
FORCEPROP 1 LAST OFFPAGE TRUE
J 0
(-500 2675);
DISPLAY 0.872340 (-500 2675);
PAINT GREEN (-500 2675);
DISPLAY INVISIBLE (-500 2675);
FORCEPROP 1 LAST COMMENT_BODY TRUE
J 0
(-700 2700);
DISPLAY 0.872340 (-700 2700);
PAINT GREEN (-700 2700);
DISPLAY INVISIBLE (-700 2700);
FORCEPROP 2 LAST PATH I109
J 0
(-1075 2850);
DISPLAY 1.021277 (-1075 2850);
DISPLAY INVISIBLE (-1075 2850);
FORCEADD OFFPAGE..4
R 2
(-825 2750);
FORCEPROP 2 LAST $XR0 233 
J 0
(-1077 2750);
DISPLAY 0.638298 (-1077 2750);
PAINT MONO (-1077 2750);
FORCEPROP 2 LAST CDS_LIB standard
J 2
(-825 2750);
DISPLAY INVISIBLE (-825 2750);
FORCEPROP 1 LAST OFFPAGE TRUE
J 2
(-1150 2625);
DISPLAY 0.872340 (-1150 2625);
DISPLAY INVISIBLE (-1150 2625);
FORCEPROP 1 LAST COMMENT_BODY TRUE
J 2
(-800 2650);
DISPLAY 0.872340 (-800 2650);
PAINT GREEN (-800 2650);
DISPLAY INVISIBLE (-800 2650);
FORCEPROP 2 LAST PATH I110
J 0
(-1075 2800);
DISPLAY 1.021277 (-1075 2800);
DISPLAY INVISIBLE (-1075 2800);
FORCEADD OFFPAGE..3
(2750 2750);
FORCEPROP 2 LAST $XR1 240 
J 0
(3084 2750);
DISPLAY 0.638298 (3084 2750);
PAINT MONO (3084 2750);
FORCEPROP 2 LAST $XR0 233 
J 0
(2964 2750);
DISPLAY 0.638298 (2964 2750);
PAINT MONO (2964 2750);
FORCEPROP 2 LAST CDS_LIB standard
J 0
(2750 2750);
DISPLAY INVISIBLE (2750 2750);
FORCEPROP 1 LAST OFFPAGE TRUE
J 0
(3075 2625);
DISPLAY 0.872340 (3075 2625);
PAINT GREEN (3075 2625);
DISPLAY INVISIBLE (3075 2625);
FORCEPROP 1 LAST COMMENT_BODY TRUE
J 0
(2700 2650);
DISPLAY 0.872340 (2700 2650);
PAINT GREEN (2700 2650);
DISPLAY INVISIBLE (2700 2650);
FORCEPROP 2 LAST PATH I113
J 2
(3025 2800);
DISPLAY 1.021277 (3025 2800);
DISPLAY INVISIBLE (3025 2800);
FORCEADD OFFPAGE..4
(2750 2800);
FORCEPROP 2 LAST $XR1 240 
J 0
(3056 2800);
DISPLAY 0.638298 (3056 2800);
PAINT MONO (3056 2800);
FORCEPROP 2 LAST $XR0 233 
J 0
(2936 2800);
DISPLAY 0.638298 (2936 2800);
PAINT MONO (2936 2800);
FORCEPROP 2 LAST CDS_LIB standard
J 0
(2750 2800);
DISPLAY INVISIBLE (2750 2800);
FORCEPROP 1 LAST OFFPAGE TRUE
J 0
(3075 2675);
DISPLAY 0.872340 (3075 2675);
DISPLAY INVISIBLE (3075 2675);
FORCEPROP 1 LAST COMMENT_BODY TRUE
J 0
(2725 2700);
DISPLAY 0.872340 (2725 2700);
PAINT GREEN (2725 2700);
DISPLAY INVISIBLE (2725 2700);
FORCEPROP 2 LAST PATH I114
J 2
(3025 2850);
DISPLAY 1.021277 (3025 2850);
DISPLAY INVISIBLE (3025 2850);
FORCEADD Q_RES..1
R 2
(1700 2800);
FORCEPROP 1 LAST PART_NUMBER CS03322FB03
J 2
(1775 2750);
DISPLAY 0.319149 (1775 2750);
DISPLAY INVISIBLE (1775 2750);
FORCEPROP 1 LAST VALUE 33.2
J 0
(1500 2800);
DISPLAY 0.404255 (1500 2800);
FORCEPROP 1 LAST TOLERANCE 1%
J 2
(1475 2800);
DISPLAY 0.404255 (1475 2800);
FORCEPROP 1 LAST MATERIAL CHIP
J 2
(1400 2800);
DISPLAY 0.404255 (1400 2800);
FORCEPROP 1 LAST $LOCATION R3712
J 2
(1875 2800);
DISPLAY 0.510638 (1875 2800);
FORCEPROP 1 LASTPIN (1800 2800) $PN 1
J 2
(1788 2812);
DISPLAY 0.787234 (1788 2812);
FORCEPROP 1 LASTPIN (1600 2800) $PN 2
J 2
(1638 2812);
DISPLAY 0.787234 (1638 2812);
FORCEPROP 1 LAST WATTAGE 1/16W
J 0
(1600 2725);
DISPLAY 0.319149 (1600 2725);
DISPLAY INVISIBLE (1600 2725);
FORCEPROP 2 LAST CDS_LIB pure_quanta
J 2
(1700 2800);
PAINT MONO (1700 2800);
DISPLAY INVISIBLE (1700 2800);
FORCEPROP 1 LAST PACK_TYPE 0402LF
J 2
(1450 2800);
DISPLAY 0.404255 (1450 2800);
DISPLAY INVISIBLE (1450 2800);
FORCEPROP 1 LAST PATH I115
J 2
(1750 2950);
DISPLAY 0.978723 (1750 2950);
PAINT WHITE (1750 2950);
DISPLAY INVISIBLE (1750 2950);
FORCEPROP 2 LAST CDS_LOCATION R3712
J 2
(1750 3000);
DISPLAY 1.021277 (1750 3000);
DISPLAY INVISIBLE (1750 3000);
FORCEPROP 2 LAST $SEC 1
J 2
(1750 3000);
DISPLAY 0.680851 (1750 3000);
PAINT MONO (1750 3000);
DISPLAY INVISIBLE (1750 3000);
FORCEPROP 2 LAST CDS_SEC 1
J 2
(1750 3000);
DISPLAY 1.021277 (1750 3000);
DISPLAY INVISIBLE (1750 3000);
FORCEADD Q_RES..1
R 2
(1700 2750);
FORCEPROP 1 LAST PART_NUMBER CS03322FB03
J 2
(1800 2875);
DISPLAY 0.404255 (1800 2875);
DISPLAY INVISIBLE (1800 2875);
FORCEPROP 1 LAST PACK_TYPE 0402LF
J 2
(1800 2925);
DISPLAY 0.404255 (1800 2925);
FORCEPROP 1 LAST VALUE 33.2
J 0
(1500 2750);
DISPLAY 0.404255 (1500 2750);
FORCEPROP 1 LAST TOLERANCE 1%
J 2
(1475 2750);
DISPLAY 0.404255 (1475 2750);
FORCEPROP 1 LAST MATERIAL CHIP
J 2
(1400 2750);
DISPLAY 0.404255 (1400 2750);
FORCEPROP 1 LAST WATTAGE 1/16W
J 0
(1575 2925);
DISPLAY 0.404255 (1575 2925);
FORCEPROP 1 LAST $LOCATION R3711
J 2
(1875 2750);
DISPLAY 0.510638 (1875 2750);
FORCEPROP 1 LASTPIN (1800 2750) $PN 1
J 2
(1788 2762);
DISPLAY 0.787234 (1788 2762);
FORCEPROP 1 LASTPIN (1600 2750) $PN 2
J 2
(1638 2762);
DISPLAY 0.787234 (1638 2762);
FORCEPROP 2 LAST CDS_LIB pure_quanta
J 2
(1700 2750);
PAINT MONO (1700 2750);
DISPLAY INVISIBLE (1700 2750);
FORCEPROP 1 LAST PATH I116
J 2
(1750 2900);
DISPLAY 0.978723 (1750 2900);
PAINT WHITE (1750 2900);
DISPLAY INVISIBLE (1750 2900);
FORCEPROP 2 LAST CDS_LOCATION R3711
J 2
(1750 2950);
DISPLAY 1.021277 (1750 2950);
DISPLAY INVISIBLE (1750 2950);
FORCEPROP 2 LAST $SEC 1
J 2
(1750 2950);
DISPLAY 0.680851 (1750 2950);
PAINT MONO (1750 2950);
DISPLAY INVISIBLE (1750 2950);
FORCEPROP 2 LAST CDS_SEC 1
J 2
(1750 2950);
DISPLAY 1.021277 (1750 2950);
DISPLAY INVISIBLE (1750 2950);
FORCEADD OFFPAGE..5
R 2
(2775 2500);
FORCEPROP 2 LAST $XR1 233 
J 0
(3084 2500);
DISPLAY 0.638298 (3084 2500);
PAINT MONO (3084 2500);
FORCEPROP 2 LAST $XR0 170 
J 0
(2964 2500);
DISPLAY 0.638298 (2964 2500);
PAINT MONO (2964 2500);
FORCEPROP 2 LAST CDS_LIB standard
J 0
(2775 2500);
DISPLAY INVISIBLE (2775 2500);
FORCEPROP 1 LAST OFFPAGE TRUE
J 2
(2450 2375);
DISPLAY 0.872340 (2450 2375);
DISPLAY INVISIBLE (2450 2375);
FORCEPROP 1 LAST COMMENT_BODY TRUE
J 2
(2675 2425);
DISPLAY 0.872340 (2675 2425);
PAINT GREEN (2675 2425);
DISPLAY INVISIBLE (2675 2425);
FORCEPROP 2 LAST PATH I117
J 0
(3100 2550);
DISPLAY 1.021277 (3100 2550);
DISPLAY INVISIBLE (3100 2550);
FORCEADD OFFPAGE..3
(2775 2550);
FORCEPROP 2 LAST $XR1 170 
J 0
(3109 2550);
DISPLAY 0.638298 (3109 2550);
PAINT MONO (3109 2550);
FORCEPROP 2 LAST $XR0 233 
J 0
(2989 2550);
DISPLAY 0.638298 (2989 2550);
PAINT MONO (2989 2550);
FORCEPROP 2 LAST CDS_LIB standard
J 0
(2775 2550);
DISPLAY INVISIBLE (2775 2550);
FORCEPROP 1 LAST OFFPAGE TRUE
J 0
(3100 2425);
DISPLAY 0.872340 (3100 2425);
DISPLAY INVISIBLE (3100 2425);
FORCEPROP 1 LAST COMMENT_BODY TRUE
J 0
(2725 2450);
DISPLAY 0.872340 (2725 2450);
PAINT GREEN (2725 2450);
DISPLAY INVISIBLE (2725 2450);
FORCEPROP 2 LAST PATH I118
J 0
(3125 2600);
DISPLAY 1.021277 (3125 2600);
DISPLAY INVISIBLE (3125 2600);
FORCEADD Q_RES..1
(1575 2550);
FORCEPROP 1 LAST PART_NUMBER CS00002JB13
J 0
(1475 2500);
DISPLAY 0.510638 (1475 2500);
DISPLAY INVISIBLE (1475 2500);
FORCEPROP 1 LAST MATERIAL CHIP
J 0
(1825 2550);
DISPLAY 0.510638 (1825 2550);
FORCEPROP 1 LAST TOLERANCE 5%
J 0
(1750 2550);
DISPLAY 0.510638 (1750 2550);
FORCEPROP 1 LAST VALUE 0
J 2
(1725 2550);
DISPLAY 0.510638 (1725 2550);
FORCEPROP 1 LAST $LOCATION R3722
J 0
(1350 2550);
DISPLAY 0.510638 (1350 2550);
FORCEPROP 2 LAST CDS_LIB pure_quanta
J 0
(1575 2550);
DISPLAY INVISIBLE (1575 2550);
FORCEPROP 1 LAST PACK_TYPE 0402LF
J 0
(1475 2450);
DISPLAY 0.510638 (1475 2450);
DISPLAY INVISIBLE (1475 2450);
FORCEPROP 1 LAST WATTAGE 1/16W
J 2
(1750 2450);
DISPLAY 0.510638 (1750 2450);
DISPLAY INVISIBLE (1750 2450);
FORCEPROP 1 LAST PATH I119
J 0
(1525 2700);
DISPLAY 0.978723 (1525 2700);
PAINT WHITE (1525 2700);
DISPLAY INVISIBLE (1525 2700);
FORCEPROP 0 LAST CDS_LOCATION R3722
J 0
(1350 2600);
DISPLAY INVISIBLE (1350 2600);
FORCEPROP 0 LAST $SEC 1
J 0
(1350 2600);
DISPLAY INVISIBLE (1350 2600);
FORCEPROP 0 LAST CDS_SEC 1
J 0
(1350 2600);
DISPLAY INVISIBLE (1350 2600);
FORCEPROP 1 LASTPIN (1475 2550) $PN 1
J 0
(1487 2562);
DISPLAY 0.787234 (1487 2562);
PAINT MONO (1487 2562);
DISPLAY INVISIBLE (1487 2562);
FORCEPROP 1 LASTPIN (1675 2550) $PN 2
J 0
(1637 2562);
DISPLAY 0.787234 (1637 2562);
PAINT MONO (1637 2562);
DISPLAY INVISIBLE (1637 2562);
FORCEADD Q_RES..1
(1575 2500);
FORCEPROP 1 LAST PART_NUMBER CS00002JB13
J 0
(1500 2450);
DISPLAY 0.319149 (1500 2450);
DISPLAY INVISIBLE (1500 2450);
FORCEPROP 1 LAST MATERIAL CHIP
J 0
(1825 2500);
DISPLAY 0.510638 (1825 2500);
FORCEPROP 1 LAST TOLERANCE 5%
J 0
(1750 2500);
DISPLAY 0.510638 (1750 2500);
FORCEPROP 1 LAST VALUE 0
J 2
(1725 2500);
DISPLAY 0.510638 (1725 2500);
FORCEPROP 1 LAST $LOCATION R3721
J 0
(1350 2500);
DISPLAY 0.510638 (1350 2500);
FORCEPROP 2 LAST CDS_LIB pure_quanta
J 0
(1575 2500);
DISPLAY INVISIBLE (1575 2500);
FORCEPROP 1 LAST WATTAGE 1/16W
J 2
(1675 2425);
DISPLAY 0.319149 (1675 2425);
DISPLAY INVISIBLE (1675 2425);
FORCEPROP 1 LAST PACK_TYPE 0402LF
J 0
(1825 2500);
DISPLAY 0.510638 (1825 2500);
DISPLAY INVISIBLE (1825 2500);
FORCEPROP 1 LAST PATH I120
J 0
(1525 2650);
DISPLAY 0.978723 (1525 2650);
PAINT WHITE (1525 2650);
DISPLAY INVISIBLE (1525 2650);
FORCEPROP 0 LAST CDS_LOCATION R3721
J 0
(1350 2550);
DISPLAY INVISIBLE (1350 2550);
FORCEPROP 0 LAST $SEC 1
J 0
(1350 2550);
DISPLAY INVISIBLE (1350 2550);
FORCEPROP 0 LAST CDS_SEC 1
J 0
(1350 2550);
DISPLAY INVISIBLE (1350 2550);
FORCEPROP 1 LASTPIN (1475 2500) $PN 1
J 0
(1487 2512);
DISPLAY 0.787234 (1487 2512);
PAINT MONO (1487 2512);
DISPLAY INVISIBLE (1487 2512);
FORCEPROP 1 LASTPIN (1675 2500) $PN 2
J 0
(1637 2512);
DISPLAY 0.787234 (1637 2512);
PAINT MONO (1637 2512);
DISPLAY INVISIBLE (1637 2512);
FORCEADD OFFPAGE..5
(-2275 2500);
FORCEPROP 2 LAST $XR1 241 
J 0
(-2680 2500);
DISPLAY 0.638298 (-2680 2500);
PAINT MONO (-2680 2500);
FORCEPROP 2 LAST $XR0 233 
J 0
(-2560 2500);
DISPLAY 0.638298 (-2560 2500);
PAINT MONO (-2560 2500);
FORCEPROP 2 LAST CDS_LIB standard
J 2
(-2275 2500);
DISPLAY INVISIBLE (-2275 2500);
FORCEPROP 1 LAST OFFPAGE TRUE
J 0
(-1950 2375);
DISPLAY 0.872340 (-1950 2375);
DISPLAY INVISIBLE (-1950 2375);
FORCEPROP 1 LAST COMMENT_BODY TRUE
J 0
(-2175 2425);
DISPLAY 0.872340 (-2175 2425);
PAINT GREEN (-2175 2425);
DISPLAY INVISIBLE (-2175 2425);
FORCEPROP 2 LAST PATH I121
J 2
(-2600 2550);
DISPLAY 1.021277 (-2600 2550);
DISPLAY INVISIBLE (-2600 2550);
FORCEADD OFFPAGE..3
R 2
(-2275 2550);
FORCEPROP 2 LAST $XR1 241 
J 0
(-2705 2550);
DISPLAY 0.638298 (-2705 2550);
PAINT MONO (-2705 2550);
FORCEPROP 2 LAST $XR0 233 
J 0
(-2585 2550);
DISPLAY 0.638298 (-2585 2550);
PAINT MONO (-2585 2550);
FORCEPROP 2 LAST CDS_LIB standard
J 2
(-2275 2550);
DISPLAY INVISIBLE (-2275 2550);
FORCEPROP 1 LAST OFFPAGE TRUE
J 2
(-2600 2425);
DISPLAY 0.872340 (-2600 2425);
DISPLAY INVISIBLE (-2600 2425);
FORCEPROP 1 LAST COMMENT_BODY TRUE
J 2
(-2225 2450);
DISPLAY 0.872340 (-2225 2450);
PAINT GREEN (-2225 2450);
DISPLAY INVISIBLE (-2225 2450);
FORCEPROP 2 LAST PATH I122
J 2
(-2625 2600);
DISPLAY 1.021277 (-2625 2600);
DISPLAY INVISIBLE (-2625 2600);
FORCEADD OFFPAGE..5
(-2275 2400);
FORCEPROP 2 LAST $XR3 305 
J 0
(-2920 2400);
DISPLAY 0.638298 (-2920 2400);
PAINT MONO (-2920 2400);
FORCEPROP 2 LAST $XR2 251 
J 0
(-2800 2400);
DISPLAY 0.638298 (-2800 2400);
PAINT MONO (-2800 2400);
FORCEPROP 2 LAST $XR1 233 
J 0
(-2680 2400);
DISPLAY 0.638298 (-2680 2400);
PAINT MONO (-2680 2400);
FORCEPROP 2 LAST $XR0 170 
J 0
(-2560 2400);
DISPLAY 0.638298 (-2560 2400);
PAINT MONO (-2560 2400);
FORCEPROP 2 LAST CDS_LIB standard
J 2
(-2275 2400);
DISPLAY INVISIBLE (-2275 2400);
FORCEPROP 1 LAST OFFPAGE TRUE
J 0
(-1950 2275);
DISPLAY 0.872340 (-1950 2275);
DISPLAY INVISIBLE (-1950 2275);
FORCEPROP 1 LAST COMMENT_BODY TRUE
J 0
(-2175 2325);
DISPLAY 0.872340 (-2175 2325);
PAINT GREEN (-2175 2325);
DISPLAY INVISIBLE (-2175 2325);
FORCEPROP 2 LAST PATH I123
J 2
(-2600 2450);
DISPLAY 1.021277 (-2600 2450);
DISPLAY INVISIBLE (-2600 2450);
FORCEADD OFFPAGE..3
R 2
(-2275 2450);
FORCEPROP 2 LAST $XR3 170 
J 0
(-2945 2450);
DISPLAY 0.638298 (-2945 2450);
PAINT MONO (-2945 2450);
FORCEPROP 2 LAST $XR2 305 
J 0
(-2825 2450);
DISPLAY 0.638298 (-2825 2450);
PAINT MONO (-2825 2450);
FORCEPROP 2 LAST $XR1 251 
J 0
(-2705 2450);
DISPLAY 0.638298 (-2705 2450);
PAINT MONO (-2705 2450);
FORCEPROP 2 LAST $XR0 233 
J 0
(-2585 2450);
DISPLAY 0.638298 (-2585 2450);
PAINT MONO (-2585 2450);
FORCEPROP 2 LAST CDS_LIB standard
J 2
(-2275 2450);
DISPLAY INVISIBLE (-2275 2450);
FORCEPROP 1 LAST OFFPAGE TRUE
J 2
(-2600 2325);
DISPLAY 0.872340 (-2600 2325);
DISPLAY INVISIBLE (-2600 2325);
FORCEPROP 1 LAST COMMENT_BODY TRUE
J 2
(-2225 2350);
DISPLAY 0.872340 (-2225 2350);
PAINT GREEN (-2225 2350);
DISPLAY INVISIBLE (-2225 2350);
FORCEPROP 2 LAST PATH I124
J 2
(-2625 2500);
DISPLAY 1.021277 (-2625 2500);
DISPLAY INVISIBLE (-2625 2500);
FORCEADD OFFPAGE..5
(-2275 2300);
FORCEPROP 2 LAST $XR1 233 
J 0
(-2680 2300);
DISPLAY 0.638298 (-2680 2300);
PAINT MONO (-2680 2300);
FORCEPROP 2 LAST $XR0 170 
J 0
(-2560 2300);
DISPLAY 0.638298 (-2560 2300);
PAINT MONO (-2560 2300);
FORCEPROP 2 LAST CDS_LIB standard
J 2
(-2275 2300);
DISPLAY INVISIBLE (-2275 2300);
FORCEPROP 1 LAST OFFPAGE TRUE
J 0
(-1950 2175);
DISPLAY 0.872340 (-1950 2175);
DISPLAY INVISIBLE (-1950 2175);
FORCEPROP 1 LAST COMMENT_BODY TRUE
J 0
(-2175 2225);
DISPLAY 0.872340 (-2175 2225);
PAINT GREEN (-2175 2225);
DISPLAY INVISIBLE (-2175 2225);
FORCEPROP 2 LAST PATH I125
J 2
(-2600 2350);
DISPLAY 1.021277 (-2600 2350);
DISPLAY INVISIBLE (-2600 2350);
FORCEADD OFFPAGE..3
R 2
(-2275 2350);
FORCEPROP 2 LAST $XR1 170 
J 0
(-2705 2350);
DISPLAY 0.638298 (-2705 2350);
PAINT MONO (-2705 2350);
FORCEPROP 2 LAST $XR0 233 
J 0
(-2585 2350);
DISPLAY 0.638298 (-2585 2350);
PAINT MONO (-2585 2350);
FORCEPROP 2 LAST CDS_LIB standard
J 2
(-2275 2350);
DISPLAY INVISIBLE (-2275 2350);
FORCEPROP 1 LAST OFFPAGE TRUE
J 2
(-2600 2225);
DISPLAY 0.872340 (-2600 2225);
DISPLAY INVISIBLE (-2600 2225);
FORCEPROP 1 LAST COMMENT_BODY TRUE
J 2
(-2225 2250);
DISPLAY 0.872340 (-2225 2250);
PAINT GREEN (-2225 2250);
DISPLAY INVISIBLE (-2225 2250);
FORCEPROP 2 LAST PATH I126
J 2
(-2625 2400);
DISPLAY 1.021277 (-2625 2400);
DISPLAY INVISIBLE (-2625 2400);
FORCEADD OFFPAGE..5
(-2275 2200);
FORCEPROP 2 LAST $XR1 233 
J 0
(-2680 2200);
DISPLAY 0.638298 (-2680 2200);
PAINT MONO (-2680 2200);
FORCEPROP 2 LAST $XR0 170 
J 0
(-2560 2200);
DISPLAY 0.638298 (-2560 2200);
PAINT MONO (-2560 2200);
FORCEPROP 2 LAST CDS_LIB standard
J 2
(-2275 2200);
DISPLAY INVISIBLE (-2275 2200);
FORCEPROP 1 LAST OFFPAGE TRUE
J 0
(-1950 2075);
DISPLAY 0.872340 (-1950 2075);
DISPLAY INVISIBLE (-1950 2075);
FORCEPROP 1 LAST COMMENT_BODY TRUE
J 0
(-2175 2125);
DISPLAY 0.872340 (-2175 2125);
PAINT GREEN (-2175 2125);
DISPLAY INVISIBLE (-2175 2125);
FORCEPROP 2 LAST PATH I127
J 2
(-2600 2250);
DISPLAY 1.021277 (-2600 2250);
DISPLAY INVISIBLE (-2600 2250);
FORCEADD OFFPAGE..3
R 2
(-2275 2250);
FORCEPROP 2 LAST $XR1 170 
J 0
(-2705 2250);
DISPLAY 0.638298 (-2705 2250);
PAINT MONO (-2705 2250);
FORCEPROP 2 LAST $XR0 233 
J 0
(-2585 2250);
DISPLAY 0.638298 (-2585 2250);
PAINT MONO (-2585 2250);
FORCEPROP 2 LAST CDS_LIB standard
J 2
(-2275 2250);
DISPLAY INVISIBLE (-2275 2250);
FORCEPROP 1 LAST OFFPAGE TRUE
J 2
(-2600 2125);
DISPLAY 0.872340 (-2600 2125);
DISPLAY INVISIBLE (-2600 2125);
FORCEPROP 1 LAST COMMENT_BODY TRUE
J 2
(-2225 2150);
DISPLAY 0.872340 (-2225 2150);
PAINT GREEN (-2225 2150);
DISPLAY INVISIBLE (-2225 2150);
FORCEPROP 2 LAST PATH I128
J 2
(-2625 2300);
DISPLAY 1.021277 (-2625 2300);
DISPLAY INVISIBLE (-2625 2300);
FORCEADD Q_RES..1
R 2
(-1075 2500);
FORCEPROP 1 LAST PART_NUMBER CS00002JB13
J 2
(-1000 2450);
DISPLAY 0.319149 (-1000 2450);
DISPLAY INVISIBLE (-1000 2450);
FORCEPROP 1 LAST MATERIAL CHIP
J 2
(-1300 2500);
DISPLAY 0.404255 (-1300 2500);
FORCEPROP 1 LAST TOLERANCE 5%
J 2
(-1250 2500);
DISPLAY 0.404255 (-1250 2500);
FORCEPROP 1 LAST VALUE 0
J 0
(-1225 2500);
DISPLAY 0.404255 (-1225 2500);
FORCEPROP 1 LAST $LOCATION R3713
J 2
(-875 2500);
DISPLAY 0.510638 (-875 2500);
FORCEPROP 1 LASTPIN (-975 2500) $PN 1
J 2
(-987 2512);
DISPLAY 0.787234 (-987 2512);
FORCEPROP 1 LASTPIN (-1175 2500) $PN 2
J 2
(-1137 2512);
DISPLAY 0.787234 (-1137 2512);
FORCEPROP 1 LAST PACK_TYPE 0402LF
J 2
(-1325 2500);
DISPLAY 0.404255 (-1325 2500);
DISPLAY INVISIBLE (-1325 2500);
FORCEPROP 2 LAST CDS_LIB pure_quanta
J 2
(-1075 2500);
PAINT MONO (-1075 2500);
DISPLAY INVISIBLE (-1075 2500);
FORCEPROP 1 LAST WATTAGE 1/16W
J 0
(-1175 2425);
DISPLAY 0.319149 (-1175 2425);
DISPLAY INVISIBLE (-1175 2425);
FORCEPROP 1 LAST PATH I137
J 2
(-1025 2650);
DISPLAY 0.978723 (-1025 2650);
PAINT WHITE (-1025 2650);
DISPLAY INVISIBLE (-1025 2650);
FORCEPROP 2 LAST CDS_LOCATION R3713
J 2
(-1025 2700);
DISPLAY 1.021277 (-1025 2700);
DISPLAY INVISIBLE (-1025 2700);
FORCEPROP 2 LAST $SEC 1
J 2
(-1025 2700);
DISPLAY 0.680851 (-1025 2700);
PAINT MONO (-1025 2700);
DISPLAY INVISIBLE (-1025 2700);
FORCEPROP 2 LAST CDS_SEC 1
J 2
(-1025 2700);
DISPLAY 1.021277 (-1025 2700);
DISPLAY INVISIBLE (-1025 2700);
FORCEADD Q_RES..1
R 2
(-1075 2550);
FORCEPROP 1 LAST PART_NUMBER CS00002JB13
J 2
(-1000 2150);
DISPLAY 0.319149 (-1000 2150);
DISPLAY INVISIBLE (-1000 2150);
FORCEPROP 1 LAST MATERIAL CHIP
J 2
(-1300 2550);
DISPLAY 0.404255 (-1300 2550);
FORCEPROP 1 LAST WATTAGE 1/16W
J 0
(-1050 2075);
DISPLAY 0.319149 (-1050 2075);
FORCEPROP 1 LAST PACK_TYPE 0402LF
J 2
(-1100 2075);
DISPLAY 0.319149 (-1100 2075);
FORCEPROP 1 LAST VALUE 0
J 0
(-1225 2550);
DISPLAY 0.404255 (-1225 2550);
FORCEPROP 1 LAST TOLERANCE 5%
J 2
(-1250 2550);
DISPLAY 0.404255 (-1250 2550);
FORCEPROP 1 LAST $LOCATION R3714
J 2
(-875 2550);
DISPLAY 0.510638 (-875 2550);
FORCEPROP 1 LASTPIN (-975 2550) $PN 1
J 2
(-987 2562);
DISPLAY 0.787234 (-987 2562);
FORCEPROP 1 LASTPIN (-1175 2550) $PN 2
J 2
(-1137 2562);
DISPLAY 0.787234 (-1137 2562);
FORCEPROP 2 LAST CDS_LIB pure_quanta
J 2
(-1075 2550);
PAINT MONO (-1075 2550);
DISPLAY INVISIBLE (-1075 2550);
FORCEPROP 1 LAST PATH I138
J 2
(-1025 2700);
DISPLAY 0.978723 (-1025 2700);
PAINT WHITE (-1025 2700);
DISPLAY INVISIBLE (-1025 2700);
FORCEPROP 2 LAST CDS_LOCATION R3714
J 2
(-1025 2750);
DISPLAY 1.021277 (-1025 2750);
DISPLAY INVISIBLE (-1025 2750);
FORCEPROP 2 LAST $SEC 1
J 2
(-1025 2750);
DISPLAY 0.680851 (-1025 2750);
PAINT MONO (-1025 2750);
DISPLAY INVISIBLE (-1025 2750);
FORCEPROP 2 LAST CDS_SEC 1
J 2
(-1025 2750);
DISPLAY 1.021277 (-1025 2750);
DISPLAY INVISIBLE (-1025 2750);
FORCEADD Q_RES..1
R 2
(-1075 2400);
FORCEPROP 1 LAST PART_NUMBER CS00002JB13
J 2
(-1000 2350);
DISPLAY 0.319149 (-1000 2350);
DISPLAY INVISIBLE (-1000 2350);
FORCEPROP 1 LAST TOLERANCE 5%
J 2
(-1250 2400);
DISPLAY 0.510638 (-1250 2400);
FORCEPROP 1 LAST MATERIAL CHIP
J 2
(-1325 2400);
DISPLAY 0.510638 (-1325 2400);
FORCEPROP 1 LAST VALUE 0
J 0
(-1225 2400);
DISPLAY 0.510638 (-1225 2400);
FORCEPROP 1 LAST $LOCATION R3715
J 2
(-850 2400);
DISPLAY 0.510638 (-850 2400);
FORCEPROP 1 LAST PACK_TYPE 0402LF
J 2
(-1325 2400);
DISPLAY 0.510638 (-1325 2400);
DISPLAY INVISIBLE (-1325 2400);
FORCEPROP 1 LAST WATTAGE 1/16W
J 0
(-1175 2325);
DISPLAY 0.319149 (-1175 2325);
DISPLAY INVISIBLE (-1175 2325);
FORCEPROP 2 LAST CDS_LIB pure_quanta
J 2
(-1075 2400);
DISPLAY INVISIBLE (-1075 2400);
FORCEPROP 1 LAST PATH I139
J 2
(-1025 2550);
DISPLAY 0.978723 (-1025 2550);
PAINT WHITE (-1025 2550);
DISPLAY INVISIBLE (-1025 2550);
FORCEPROP 0 LAST CDS_LOCATION R3715
J 2
(-850 2450);
DISPLAY INVISIBLE (-850 2450);
FORCEPROP 0 LAST $SEC 1
J 2
(-850 2450);
DISPLAY INVISIBLE (-850 2450);
FORCEPROP 0 LAST CDS_SEC 1
J 2
(-850 2450);
DISPLAY INVISIBLE (-850 2450);
FORCEPROP 1 LASTPIN (-975 2400) $PN 1
J 2
(-987 2412);
DISPLAY 0.787234 (-987 2412);
PAINT MONO (-987 2412);
DISPLAY INVISIBLE (-987 2412);
FORCEPROP 1 LASTPIN (-1175 2400) $PN 2
J 2
(-1137 2412);
DISPLAY 0.787234 (-1137 2412);
PAINT MONO (-1137 2412);
DISPLAY INVISIBLE (-1137 2412);
FORCEADD Q_RES..1
R 2
(-1075 2450);
FORCEPROP 1 LAST PART_NUMBER CS00002JB13
J 2
(-1000 2575);
DISPLAY 0.319149 (-1000 2575);
DISPLAY INVISIBLE (-1000 2575);
FORCEPROP 1 LAST TOLERANCE 5%
J 2
(-1250 2450);
DISPLAY 0.510638 (-1250 2450);
FORCEPROP 1 LAST MATERIAL CHIP
J 2
(-1325 2450);
DISPLAY 0.510638 (-1325 2450);
FORCEPROP 1 LAST VALUE 0
J 0
(-1225 2450);
DISPLAY 0.510638 (-1225 2450);
FORCEPROP 1 LAST $LOCATION R3716
J 2
(-850 2450);
DISPLAY 0.510638 (-850 2450);
FORCEPROP 2 LAST CDS_LIB pure_quanta
J 2
(-1075 2450);
DISPLAY INVISIBLE (-1075 2450);
FORCEPROP 1 LAST PACK_TYPE 0402LF
J 2
(-1325 2450);
DISPLAY 0.510638 (-1325 2450);
DISPLAY INVISIBLE (-1325 2450);
FORCEPROP 1 LAST WATTAGE 1/16W
J 0
(-1175 2600);
DISPLAY 0.319149 (-1175 2600);
DISPLAY INVISIBLE (-1175 2600);
FORCEPROP 1 LAST PATH I140
J 2
(-1025 2600);
DISPLAY 0.978723 (-1025 2600);
PAINT WHITE (-1025 2600);
DISPLAY INVISIBLE (-1025 2600);
FORCEPROP 0 LAST CDS_LOCATION R3716
J 2
(-850 2500);
DISPLAY INVISIBLE (-850 2500);
FORCEPROP 0 LAST $SEC 1
J 2
(-850 2500);
DISPLAY INVISIBLE (-850 2500);
FORCEPROP 0 LAST CDS_SEC 1
J 2
(-850 2500);
DISPLAY INVISIBLE (-850 2500);
FORCEPROP 1 LASTPIN (-975 2450) $PN 1
J 2
(-987 2462);
DISPLAY 0.787234 (-987 2462);
PAINT MONO (-987 2462);
DISPLAY INVISIBLE (-987 2462);
FORCEPROP 1 LASTPIN (-1175 2450) $PN 2
J 2
(-1137 2462);
DISPLAY 0.787234 (-1137 2462);
PAINT MONO (-1137 2462);
DISPLAY INVISIBLE (-1137 2462);
FORCEADD Q_RES..1
R 2
(-1075 2300);
FORCEPROP 1 LAST PART_NUMBER CS00002JB13
J 2
(-1000 2250);
DISPLAY 0.319149 (-1000 2250);
DISPLAY INVISIBLE (-1000 2250);
FORCEPROP 1 LAST TOLERANCE 5%
J 2
(-1250 2300);
DISPLAY 0.510638 (-1250 2300);
FORCEPROP 1 LAST MATERIAL CHIP
J 2
(-1325 2300);
DISPLAY 0.510638 (-1325 2300);
FORCEPROP 1 LAST VALUE 0
J 0
(-1225 2300);
DISPLAY 0.510638 (-1225 2300);
FORCEPROP 1 LAST $LOCATION R3717
J 2
(-850 2300);
DISPLAY 0.510638 (-850 2300);
FORCEPROP 1 LAST PACK_TYPE 0402LF
J 2
(-1325 2300);
DISPLAY 0.510638 (-1325 2300);
DISPLAY INVISIBLE (-1325 2300);
FORCEPROP 1 LAST WATTAGE 1/16W
J 0
(-1175 2225);
DISPLAY 0.319149 (-1175 2225);
DISPLAY INVISIBLE (-1175 2225);
FORCEPROP 2 LAST CDS_LIB pure_quanta
J 2
(-1075 2300);
DISPLAY INVISIBLE (-1075 2300);
FORCEPROP 1 LAST PATH I141
J 2
(-1025 2450);
DISPLAY 0.978723 (-1025 2450);
PAINT WHITE (-1025 2450);
DISPLAY INVISIBLE (-1025 2450);
FORCEPROP 0 LAST CDS_LOCATION R3717
J 2
(-850 2350);
DISPLAY INVISIBLE (-850 2350);
FORCEPROP 0 LAST $SEC 1
J 2
(-850 2350);
DISPLAY INVISIBLE (-850 2350);
FORCEPROP 0 LAST CDS_SEC 1
J 2
(-850 2350);
DISPLAY INVISIBLE (-850 2350);
FORCEPROP 1 LASTPIN (-975 2300) $PN 1
J 2
(-987 2312);
DISPLAY 0.787234 (-987 2312);
PAINT MONO (-987 2312);
DISPLAY INVISIBLE (-987 2312);
FORCEPROP 1 LASTPIN (-1175 2300) $PN 2
J 2
(-1137 2312);
DISPLAY 0.787234 (-1137 2312);
PAINT MONO (-1137 2312);
DISPLAY INVISIBLE (-1137 2312);
FORCEADD Q_RES..1
R 2
(-1075 2350);
FORCEPROP 1 LAST PART_NUMBER CS00002JB13
J 2
(-975 2300);
DISPLAY 0.510638 (-975 2300);
DISPLAY INVISIBLE (-975 2300);
FORCEPROP 1 LAST MATERIAL CHIP
J 2
(-1325 2350);
DISPLAY 0.510638 (-1325 2350);
FORCEPROP 1 LAST VALUE 0
J 0
(-1225 2350);
DISPLAY 0.510638 (-1225 2350);
FORCEPROP 1 LAST TOLERANCE 5%
J 2
(-1250 2350);
DISPLAY 0.510638 (-1250 2350);
FORCEPROP 1 LAST $LOCATION R3718
J 2
(-850 2350);
DISPLAY 0.510638 (-850 2350);
FORCEPROP 2 LAST CDS_LIB pure_quanta
J 2
(-1075 2350);
DISPLAY INVISIBLE (-1075 2350);
FORCEPROP 1 LAST PACK_TYPE 0402LF
J 2
(-975 2250);
DISPLAY 0.510638 (-975 2250);
DISPLAY INVISIBLE (-975 2250);
FORCEPROP 1 LAST WATTAGE 1/16W
J 0
(-1250 2250);
DISPLAY 0.510638 (-1250 2250);
DISPLAY INVISIBLE (-1250 2250);
FORCEPROP 1 LAST PATH I142
J 2
(-1025 2500);
DISPLAY 0.978723 (-1025 2500);
PAINT WHITE (-1025 2500);
DISPLAY INVISIBLE (-1025 2500);
FORCEPROP 0 LAST CDS_LOCATION R3718
J 2
(-850 2400);
DISPLAY INVISIBLE (-850 2400);
FORCEPROP 0 LAST $SEC 1
J 2
(-850 2400);
DISPLAY INVISIBLE (-850 2400);
FORCEPROP 0 LAST CDS_SEC 1
J 2
(-850 2400);
DISPLAY INVISIBLE (-850 2400);
FORCEPROP 1 LASTPIN (-975 2350) $PN 1
J 2
(-987 2362);
DISPLAY 0.787234 (-987 2362);
PAINT MONO (-987 2362);
DISPLAY INVISIBLE (-987 2362);
FORCEPROP 1 LASTPIN (-1175 2350) $PN 2
J 2
(-1137 2362);
DISPLAY 0.787234 (-1137 2362);
PAINT MONO (-1137 2362);
DISPLAY INVISIBLE (-1137 2362);
FORCEADD Q_RES..1
R 2
(-1075 2200);
FORCEPROP 1 LAST PART_NUMBER CS00002JB13
J 2
(-1000 2150);
DISPLAY 0.319149 (-1000 2150);
DISPLAY INVISIBLE (-1000 2150);
FORCEPROP 1 LAST MATERIAL CHIP
J 2
(-1325 2200);
DISPLAY 0.510638 (-1325 2200);
FORCEPROP 1 LAST VALUE 0
J 0
(-1225 2200);
DISPLAY 0.510638 (-1225 2200);
FORCEPROP 1 LAST TOLERANCE 5%
J 2
(-1250 2200);
DISPLAY 0.510638 (-1250 2200);
FORCEPROP 1 LAST $LOCATION R3719
J 2
(-850 2200);
DISPLAY 0.510638 (-850 2200);
FORCEPROP 2 LAST CDS_LIB pure_quanta
J 2
(-1075 2200);
DISPLAY INVISIBLE (-1075 2200);
FORCEPROP 1 LAST WATTAGE 1/16W
J 0
(-1175 2125);
DISPLAY 0.319149 (-1175 2125);
DISPLAY INVISIBLE (-1175 2125);
FORCEPROP 1 LAST PACK_TYPE 0402LF
J 2
(-1325 2200);
DISPLAY 0.510638 (-1325 2200);
DISPLAY INVISIBLE (-1325 2200);
FORCEPROP 1 LAST PATH I143
J 2
(-1025 2350);
DISPLAY 0.978723 (-1025 2350);
PAINT WHITE (-1025 2350);
DISPLAY INVISIBLE (-1025 2350);
FORCEPROP 0 LAST CDS_LOCATION R3719
J 2
(-850 2250);
DISPLAY INVISIBLE (-850 2250);
FORCEPROP 0 LAST $SEC 1
J 2
(-850 2250);
DISPLAY INVISIBLE (-850 2250);
FORCEPROP 0 LAST CDS_SEC 1
J 2
(-850 2250);
DISPLAY INVISIBLE (-850 2250);
FORCEPROP 1 LASTPIN (-975 2200) $PN 1
J 2
(-987 2212);
DISPLAY 0.787234 (-987 2212);
PAINT MONO (-987 2212);
DISPLAY INVISIBLE (-987 2212);
FORCEPROP 1 LASTPIN (-1175 2200) $PN 2
J 2
(-1137 2212);
DISPLAY 0.787234 (-1137 2212);
PAINT MONO (-1137 2212);
DISPLAY INVISIBLE (-1137 2212);
FORCEADD Q_RES..1
R 2
(-1075 2250);
FORCEPROP 1 LAST PART_NUMBER CS00002JB13
J 2
(-975 2200);
DISPLAY 0.510638 (-975 2200);
DISPLAY INVISIBLE (-975 2200);
FORCEPROP 1 LAST TOLERANCE 5%
J 2
(-1250 2250);
DISPLAY 0.510638 (-1250 2250);
FORCEPROP 1 LAST MATERIAL CHIP
J 2
(-1325 2250);
DISPLAY 0.510638 (-1325 2250);
FORCEPROP 1 LAST VALUE 0
J 0
(-1225 2250);
DISPLAY 0.510638 (-1225 2250);
FORCEPROP 1 LAST $LOCATION R3720
J 2
(-850 2250);
DISPLAY 0.510638 (-850 2250);
FORCEPROP 1 LAST WATTAGE 1/16W
J 0
(-1250 2150);
DISPLAY 0.510638 (-1250 2150);
DISPLAY INVISIBLE (-1250 2150);
FORCEPROP 1 LAST PACK_TYPE 0402LF
J 2
(-975 2150);
DISPLAY 0.510638 (-975 2150);
DISPLAY INVISIBLE (-975 2150);
FORCEPROP 2 LAST CDS_LIB pure_quanta
J 2
(-1075 2250);
DISPLAY INVISIBLE (-1075 2250);
FORCEPROP 1 LAST PATH I144
J 2
(-1025 2400);
DISPLAY 0.978723 (-1025 2400);
PAINT WHITE (-1025 2400);
DISPLAY INVISIBLE (-1025 2400);
FORCEPROP 0 LAST CDS_LOCATION R3720
J 2
(-850 2300);
DISPLAY INVISIBLE (-850 2300);
FORCEPROP 0 LAST $SEC 1
J 2
(-850 2300);
DISPLAY INVISIBLE (-850 2300);
FORCEPROP 0 LAST CDS_SEC 1
J 2
(-850 2300);
DISPLAY INVISIBLE (-850 2300);
FORCEPROP 1 LASTPIN (-975 2250) $PN 1
J 2
(-987 2262);
DISPLAY 0.787234 (-987 2262);
PAINT MONO (-987 2262);
DISPLAY INVISIBLE (-987 2262);
FORCEPROP 1 LASTPIN (-1175 2250) $PN 2
J 2
(-1137 2262);
DISPLAY 0.787234 (-1137 2262);
PAINT MONO (-1137 2262);
DISPLAY INVISIBLE (-1137 2262);
FORCEADD Q_RES..1
(-1325 2650);
FORCEPROP 1 LAST PART_NUMBER CS00002JB13
J 0
(-1400 2600);
DISPLAY 0.319149 (-1400 2600);
DISPLAY INVISIBLE (-1400 2600);
FORCEPROP 1 LAST TOLERANCE 5%
J 0
(-1150 2650);
DISPLAY 0.510638 (-1150 2650);
FORCEPROP 1 LAST MATERIAL CHIP
J 0
(-1075 2650);
DISPLAY 0.510638 (-1075 2650);
FORCEPROP 1 LAST VALUE 0
J 2
(-1175 2650);
DISPLAY 0.510638 (-1175 2650);
FORCEPROP 1 LAST $LOCATION R3710
J 0
(-1550 2650);
DISPLAY 0.638298 (-1550 2650);
FORCEPROP 1 LASTPIN (-1425 2650) $PN 1
J 0
(-1413 2662);
DISPLAY 0.787234 (-1413 2662);
PAINT MONO (-1413 2662);
FORCEPROP 1 LASTPIN (-1225 2650) $PN 2
J 0
(-1263 2662);
DISPLAY 0.787234 (-1263 2662);
PAINT MONO (-1263 2662);
FORCEPROP 1 LAST PACK_TYPE 0402LF
J 0
(-1075 2650);
DISPLAY 0.510638 (-1075 2650);
DISPLAY INVISIBLE (-1075 2650);
FORCEPROP 1 LAST WATTAGE 1/16W
J 2
(-1225 2575);
DISPLAY 0.319149 (-1225 2575);
DISPLAY INVISIBLE (-1225 2575);
FORCEPROP 2 LAST CDS_LIB pure_quanta
J 0
(-1325 2650);
DISPLAY INVISIBLE (-1325 2650);
FORCEPROP 1 LAST PATH I145
J 0
(-1375 2800);
DISPLAY 0.978723 (-1375 2800);
PAINT WHITE (-1375 2800);
DISPLAY INVISIBLE (-1375 2800);
FORCEPROP 0 LAST CDS_LOCATION R3710
J 0
(-1550 2700);
DISPLAY 1.021277 (-1550 2700);
DISPLAY INVISIBLE (-1550 2700);
FORCEPROP 0 LAST $SEC 1
J 0
(-1550 2700);
DISPLAY 0.680851 (-1550 2700);
PAINT MONO (-1550 2700);
DISPLAY INVISIBLE (-1550 2700);
FORCEPROP 0 LAST CDS_SEC 1
J 0
(-1550 2700);
DISPLAY 1.021277 (-1550 2700);
DISPLAY INVISIBLE (-1550 2700);
FORCEADD UNIVERSAL_POWER..1
(-2425 3275);
FORCEPROP 3 LASTPIN (-2425 3225) SIG_NAME P3V3_AUX\g
J 0
(-2415 3235);
DISPLAY 0.659574 (-2415 3235);
PAINT MONO (-2415 3235);
DISPLAY INVISIBLE (-2415 3235);
FORCEPROP 1 LAST HDL_POWER P3V3_AUX
J 1
(-2425 3325);
DISPLAY 0.872340 (-2425 3325);
PAINT GREEN (-2425 3325);
FORCEPROP 2 LAST CDS_LIB logical_power
J 0
(-2425 3275);
DISPLAY INVISIBLE (-2425 3275);
FORCEPROP 1 LAST PATH I146
J 0
(-2375 3300);
DISPLAY 0.872340 (-2375 3300);
PAINT AQUA (-2375 3300);
DISPLAY INVISIBLE (-2375 3300);
FORCEADD Q_RES..2
R 2
(-2425 3000);
FORCEPROP 1 LAST PART_NUMBER CS31002FB08
J 2
(-2465 2825);
DISPLAY 0.638298 (-2465 2825);
DISPLAY INVISIBLE (-2465 2825);
FORCEPROP 1 LAST TOLERANCE 1%
J 2
(-2470 3025);
DISPLAY 0.638298 (-2470 3025);
FORCEPROP 1 LAST MATERIAL EMPTY
J 2
(-2465 2925);
DISPLAY 0.638298 (-2465 2925);
PAINT RED (-2465 2925);
FORCEPROP 1 LAST PACK_TYPE 0402LF
J 2
(-2465 2875);
DISPLAY 0.638298 (-2465 2875);
FORCEPROP 1 LAST VALUE 10K
J 2
(-2470 3075);
DISPLAY 0.638298 (-2470 3075);
FORCEPROP 1 LAST WATTAGE 1/16W
J 2
(-2465 2975);
DISPLAY 0.638298 (-2465 2975);
FORCEPROP 1 LAST $LOCATION R3705
J 2
(-2470 3125);
DISPLAY 0.978723 (-2470 3125);
FORCEPROP 1 LASTPIN (-2425 3100) $PN 1
J 2
(-2430 3062);
DISPLAY 0.787234 (-2430 3062);
FORCEPROP 1 LASTPIN (-2425 2900) $PN 2
J 2
(-2430 2910);
DISPLAY 0.787234 (-2430 2910);
FORCEPROP 2 LAST CDS_LIB pure_quanta
J 2
(-2425 3000);
PAINT MONO (-2425 3000);
DISPLAY INVISIBLE (-2425 3000);
FORCEPROP 1 LAST PATH I147
J 2
(-2475 3175);
DISPLAY 0.978723 (-2475 3175);
PAINT WHITE (-2475 3175);
DISPLAY INVISIBLE (-2475 3175);
FORCEPROP 2 LAST CDS_LOCATION R3705
J 0
(-2475 3225);
DISPLAY 1.021277 (-2475 3225);
DISPLAY INVISIBLE (-2475 3225);
FORCEPROP 2 LAST $SEC 1
J 0
(-2475 3225);
DISPLAY 0.680851 (-2475 3225);
PAINT MONO (-2475 3225);
DISPLAY INVISIBLE (-2475 3225);
FORCEPROP 2 LAST CDS_SEC 1
J 0
(-2475 3225);
DISPLAY 1.021277 (-2475 3225);
DISPLAY INVISIBLE (-2475 3225);
FORCEADD OFFPAGE..1
(-2950 2650);
FORCEPROP 2 LAST $XR7 245 
J 0
(-4042 2650);
DISPLAY 0.638298 (-4042 2650);
PAINT MONO (-4042 2650);
FORCEPROP 2 LAST $XR6 236 
J 0
(-3922 2650);
DISPLAY 0.638298 (-3922 2650);
PAINT MONO (-3922 2650);
FORCEPROP 2 LAST $XR5 231 
J 0
(-3802 2650);
DISPLAY 0.638298 (-3802 2650);
PAINT MONO (-3802 2650);
FORCEPROP 2 LAST $XR4 227 
J 0
(-3682 2650);
DISPLAY 0.638298 (-3682 2650);
PAINT MONO (-3682 2650);
FORCEPROP 2 LAST $XR3 191 
J 0
(-3562 2650);
DISPLAY 0.638298 (-3562 2650);
PAINT MONO (-3562 2650);
FORCEPROP 2 LAST $XR2 161 
J 0
(-3442 2650);
DISPLAY 0.638298 (-3442 2650);
PAINT MONO (-3442 2650);
FORCEPROP 2 LAST $XR1 154 
J 0
(-3322 2650);
DISPLAY 0.638298 (-3322 2650);
PAINT MONO (-3322 2650);
FORCEPROP 2 LAST $XR0 215 
J 0
(-3202 2650);
DISPLAY 0.638298 (-3202 2650);
PAINT MONO (-3202 2650);
FORCEPROP 2 LAST CDS_LIB standard
J 0
(-2950 2650);
DISPLAY INVISIBLE (-2950 2650);
FORCEPROP 1 LAST OFFPAGE TRUE
J 0
(-2625 2525);
DISPLAY 0.872340 (-2625 2525);
DISPLAY INVISIBLE (-2625 2525);
FORCEPROP 1 LAST COMMENT_BODY TRUE
J 0
(-2825 2550);
DISPLAY 0.872340 (-2825 2550);
PAINT GREEN (-2825 2550);
DISPLAY INVISIBLE (-2825 2550);
FORCEPROP 2 LAST PATH I148
J 0
(-3225 2700);
DISPLAY 1.021277 (-3225 2700);
DISPLAY INVISIBLE (-3225 2700);
FORCEADD UNIVERSAL_GND..1
(700 1925);
FORCEPROP 3 LASTPIN (700 1975) SIG_NAME GND\g
J 0
(710 1985);
DISPLAY 0.659574 (710 1985);
PAINT MONO (710 1985);
DISPLAY INVISIBLE (710 1985);
FORCEPROP 2 LAST CDS_LIB logical_power
J 0
(700 1925);
DISPLAY INVISIBLE (700 1925);
FORCEPROP 1 LAST HDL_POWER GND
J 1
(725 1850);
DISPLAY 0.872340 (725 1850);
PAINT GREEN (725 1850);
DISPLAY INVISIBLE (725 1850);
FORCEPROP 1 LAST PATH I149
J 0
(775 1925);
DISPLAY 0.872340 (775 1925);
PAINT AQUA (775 1925);
DISPLAY INVISIBLE (775 1925);
FORCEADD Q_RES..2
(-3150 75);
FORCEPROP 1 LAST PART_NUMBER CS21002FB06
J 0
(-3110 -50);
DISPLAY 0.510638 (-3110 -50);
DISPLAY INVISIBLE (-3110 -50);
FORCEPROP 1 LAST VALUE 1K
J 0
(-3105 150);
DISPLAY 0.638298 (-3105 150);
FORCEPROP 1 LAST PACK_TYPE 0402LF
J 0
(-3110 -50);
DISPLAY 0.638298 (-3110 -50);
FORCEPROP 1 LAST MATERIAL CHIP
J 0
(-3110 0);
DISPLAY 0.638298 (-3110 0);
FORCEPROP 1 LAST WATTAGE 1/16W
J 0
(-3110 50);
DISPLAY 0.638298 (-3110 50);
FORCEPROP 1 LAST TOLERANCE 1%
J 0
(-3105 100);
DISPLAY 0.638298 (-3105 100);
FORCEPROP 1 LAST $LOCATION R3704
J 0
(-3105 200);
DISPLAY 0.978723 (-3105 200);
FORCEPROP 1 LASTPIN (-3150 175) $PN 1
J 0
(-3145 137);
DISPLAY 0.787234 (-3145 137);
FORCEPROP 1 LASTPIN (-3150 -25) $PN 2
J 0
(-3145 -15);
DISPLAY 0.787234 (-3145 -15);
FORCEPROP 2 LAST CDS_LIB pure_quanta
J 0
(-3150 75);
PAINT MONO (-3150 75);
DISPLAY INVISIBLE (-3150 75);
FORCEPROP 1 LAST PATH I2
J 0
(-3100 250);
DISPLAY 0.978723 (-3100 250);
PAINT WHITE (-3100 250);
DISPLAY INVISIBLE (-3100 250);
FORCEPROP 2 LAST CDS_LOCATION R3704
J 0
(-3100 300);
DISPLAY 1.021277 (-3100 300);
DISPLAY INVISIBLE (-3100 300);
FORCEPROP 2 LAST $SEC 1
J 0
(-3100 300);
DISPLAY 0.680851 (-3100 300);
PAINT MONO (-3100 300);
DISPLAY INVISIBLE (-3100 300);
FORCEPROP 2 LAST CDS_SEC 1
J 0
(-3100 300);
DISPLAY 1.021277 (-3100 300);
DISPLAY INVISIBLE (-3100 300);
FORCEADD Q_RES..2
(-3150 725);
FORCEPROP 1 LAST PART_NUMBER CS31002FB08
J 0
(-3110 600);
DISPLAY 0.510638 (-3110 600);
DISPLAY INVISIBLE (-3110 600);
FORCEPROP 1 LAST MATERIAL EMPTY
J 0
(-3110 650);
DISPLAY 0.638298 (-3110 650);
PAINT RED (-3110 650);
FORCEPROP 1 LAST TOLERANCE 1%
J 0
(-3105 750);
DISPLAY 0.638298 (-3105 750);
FORCEPROP 1 LAST PACK_TYPE 0402LF
J 0
(-3110 600);
DISPLAY 0.638298 (-3110 600);
FORCEPROP 1 LAST VALUE 10K
J 0
(-3105 800);
DISPLAY 0.638298 (-3105 800);
FORCEPROP 1 LAST WATTAGE 1/16W
J 0
(-3110 700);
DISPLAY 0.638298 (-3110 700);
FORCEPROP 1 LAST $LOCATION R3703
J 0
(-3105 850);
DISPLAY 0.978723 (-3105 850);
FORCEPROP 1 LASTPIN (-3150 825) $PN 1
J 0
(-3145 787);
DISPLAY 0.787234 (-3145 787);
FORCEPROP 1 LASTPIN (-3150 625) $PN 2
J 0
(-3145 635);
DISPLAY 0.787234 (-3145 635);
FORCEPROP 2 LAST CDS_LIB pure_quanta
J 0
(-3150 725);
PAINT MONO (-3150 725);
DISPLAY INVISIBLE (-3150 725);
FORCEPROP 1 LAST PATH I3
J 0
(-3100 900);
DISPLAY 0.978723 (-3100 900);
PAINT WHITE (-3100 900);
DISPLAY INVISIBLE (-3100 900);
FORCEPROP 2 LAST CDS_LOCATION R3703
J 0
(-3100 950);
DISPLAY 1.021277 (-3100 950);
DISPLAY INVISIBLE (-3100 950);
FORCEPROP 2 LAST $SEC 1
J 0
(-3100 950);
DISPLAY 0.680851 (-3100 950);
PAINT MONO (-3100 950);
DISPLAY INVISIBLE (-3100 950);
FORCEPROP 2 LAST CDS_SEC 1
J 0
(-3100 950);
DISPLAY 1.021277 (-3100 950);
DISPLAY INVISIBLE (-3100 950);
FORCEADD OFFPAGE..2
(3375 -225);
FORCEPROP 2 LAST $XR1 170 
J 0
(3684 -225);
DISPLAY 0.638298 (3684 -225);
PAINT MONO (3684 -225);
FORCEPROP 2 LAST $XR0 233 
J 0
(3564 -225);
DISPLAY 0.638298 (3564 -225);
PAINT MONO (3564 -225);
FORCEPROP 2 LAST CDS_LIB standard
J 0
(3375 -225);
PAINT MONO (3375 -225);
DISPLAY INVISIBLE (3375 -225);
FORCEPROP 1 LAST OFFPAGE TRUE
J 0
(3700 -350);
DISPLAY 0.872340 (3700 -350);
PAINT GREEN (3700 -350);
DISPLAY INVISIBLE (3700 -350);
FORCEPROP 1 LAST COMMENT_BODY TRUE
J 0
(3330 -320);
DISPLAY 0.872340 (3330 -320);
PAINT GREEN (3330 -320);
DISPLAY INVISIBLE (3330 -320);
FORCEPROP 2 LAST PATH I33
J 0
(3700 -175);
DISPLAY 1.021277 (3700 -175);
DISPLAY INVISIBLE (3700 -175);
FORCEADD Q_RES..1
(1975 -225);
FORCEPROP 1 LAST PART_NUMBER CS22202JB07
J 0
(1875 -175);
DISPLAY 0.510638 (1875 -175);
DISPLAY INVISIBLE (1875 -175);
FORCEPROP 1 LAST MATERIAL CHIP
J 0
(2325 -225);
DISPLAY 0.510638 (2325 -225);
FORCEPROP 1 LAST VALUE 2.2K
J 2
(2225 -225);
DISPLAY 0.510638 (2225 -225);
FORCEPROP 1 LAST TOLERANCE 5%
J 0
(2225 -225);
DISPLAY 0.510638 (2225 -225);
FORCEPROP 1 LAST $LOCATION R3732
J 0
(1725 -225);
DISPLAY 0.638298 (1725 -225);
FORCEPROP 1 LASTPIN (1875 -225) $PN 1
J 0
(1887 -213);
DISPLAY 0.787234 (1887 -213);
FORCEPROP 1 LASTPIN (2075 -225) $PN 2
J 0
(2037 -213);
DISPLAY 0.787234 (2037 -213);
FORCEPROP 2 LAST CDS_LIB pure_quanta
J 0
(1975 -225);
PAINT MONO (1975 -225);
DISPLAY INVISIBLE (1975 -225);
FORCEPROP 1 LAST PACK_TYPE 0402LF
J 0
(1875 -125);
DISPLAY 0.510638 (1875 -125);
DISPLAY INVISIBLE (1875 -125);
FORCEPROP 1 LAST WATTAGE 1/16W
J 2
(2175 -125);
DISPLAY 0.510638 (2175 -125);
DISPLAY INVISIBLE (2175 -125);
FORCEPROP 1 LAST PATH I34
J 0
(1925 -75);
DISPLAY 0.978723 (1925 -75);
PAINT WHITE (1925 -75);
DISPLAY INVISIBLE (1925 -75);
FORCEPROP 2 LAST CDS_LOCATION R3732
J 0
(1925 -25);
DISPLAY 1.021277 (1925 -25);
DISPLAY INVISIBLE (1925 -25);
FORCEPROP 2 LAST $SEC 1
J 0
(1925 -25);
DISPLAY 0.680851 (1925 -25);
PAINT MONO (1925 -25);
DISPLAY INVISIBLE (1925 -25);
FORCEPROP 2 LAST CDS_SEC 1
J 0
(1925 -25);
DISPLAY 1.021277 (1925 -25);
DISPLAY INVISIBLE (1925 -25);
FORCEADD OFFPAGE..2
(-1475 300);
FORCEPROP 2 LAST $XR0 233 
J 0
(-1286 300);
DISPLAY 0.638298 (-1286 300);
PAINT MONO (-1286 300);
FORCEPROP 2 LAST CDS_LIB standard
J 0
(-1475 300);
PAINT MONO (-1475 300);
DISPLAY INVISIBLE (-1475 300);
FORCEPROP 1 LAST OFFPAGE TRUE
J 0
(-1150 175);
DISPLAY 0.872340 (-1150 175);
DISPLAY INVISIBLE (-1150 175);
FORCEPROP 1 LAST COMMENT_BODY TRUE
J 0
(-1520 205);
DISPLAY 0.872340 (-1520 205);
PAINT GREEN (-1520 205);
DISPLAY INVISIBLE (-1520 205);
FORCEPROP 2 LAST PATH I35
J 0
(-1275 350);
DISPLAY 1.021277 (-1275 350);
DISPLAY INVISIBLE (-1275 350);
FORCEADD OFFPAGE..2
(-1475 375);
FORCEPROP 2 LAST $XR0 233 
J 0
(-1286 375);
DISPLAY 0.638298 (-1286 375);
PAINT MONO (-1286 375);
FORCEPROP 2 LAST CDS_LIB standard
J 0
(-1475 375);
PAINT MONO (-1475 375);
DISPLAY INVISIBLE (-1475 375);
FORCEPROP 1 LAST OFFPAGE TRUE
J 0
(-1150 250);
DISPLAY 0.872340 (-1150 250);
DISPLAY INVISIBLE (-1150 250);
FORCEPROP 1 LAST COMMENT_BODY TRUE
J 0
(-1520 280);
DISPLAY 0.872340 (-1520 280);
PAINT GREEN (-1520 280);
DISPLAY INVISIBLE (-1520 280);
FORCEPROP 2 LAST PATH I36
J 0
(-1275 425);
DISPLAY 1.021277 (-1275 425);
DISPLAY INVISIBLE (-1275 425);
FORCEADD OFFPAGE..2
(-1475 450);
FORCEPROP 2 LAST $XR0 233 
J 0
(-1286 450);
DISPLAY 0.638298 (-1286 450);
PAINT MONO (-1286 450);
FORCEPROP 2 LAST CDS_LIB standard
J 0
(-1475 450);
PAINT MONO (-1475 450);
DISPLAY INVISIBLE (-1475 450);
FORCEPROP 1 LAST OFFPAGE TRUE
J 0
(-1150 325);
DISPLAY 0.872340 (-1150 325);
DISPLAY INVISIBLE (-1150 325);
FORCEPROP 1 LAST COMMENT_BODY TRUE
J 0
(-1520 355);
DISPLAY 0.872340 (-1520 355);
PAINT GREEN (-1520 355);
DISPLAY INVISIBLE (-1520 355);
FORCEPROP 2 LAST PATH I37
J 0
(-1275 500);
DISPLAY 1.021277 (-1275 500);
DISPLAY INVISIBLE (-1275 500);
FORCEADD UNIVERSAL_POWER..1
(-3150 1100);
FORCEPROP 3 LASTPIN (-3150 1050) SIG_NAME P3V3_AUX\g
J 0
(-3140 1060);
DISPLAY 0.659574 (-3140 1060);
PAINT MONO (-3140 1060);
DISPLAY INVISIBLE (-3140 1060);
FORCEPROP 1 LAST HDL_POWER P3V3_AUX
J 1
(-3150 1150);
DISPLAY 0.872340 (-3150 1150);
PAINT GREEN (-3150 1150);
FORCEPROP 2 LAST CDS_LIB logical_power
J 0
(-3150 1100);
PAINT MONO (-3150 1100);
DISPLAY INVISIBLE (-3150 1100);
FORCEPROP 1 LAST PATH I4
J 0
(-3100 1125);
DISPLAY 0.872340 (-3100 1125);
PAINT AQUA (-3100 1125);
DISPLAY INVISIBLE (-3100 1125);
FORCEADD Q_RES..1
(1975 125);
FORCEPROP 1 LAST PART_NUMBER CS22202JB07
J 0
(1825 200);
DISPLAY 0.510638 (1825 200);
DISPLAY INVISIBLE (1825 200);
FORCEPROP 1 LAST VALUE 2.2K
J 2
(2200 125);
DISPLAY 0.510638 (2200 125);
FORCEPROP 1 LAST PACK_TYPE 0402LF
J 0
(1825 250);
DISPLAY 0.510638 (1825 250);
FORCEPROP 1 LAST MATERIAL CHIP
J 0
(2275 125);
DISPLAY 0.510638 (2275 125);
FORCEPROP 1 LAST TOLERANCE 5%
J 0
(2200 125);
DISPLAY 0.510638 (2200 125);
FORCEPROP 1 LAST WATTAGE 1/16W
J 2
(2125 250);
DISPLAY 0.510638 (2125 250);
FORCEPROP 1 LAST $LOCATION R3729
J 0
(1725 125);
DISPLAY 0.510638 (1725 125);
FORCEPROP 1 LASTPIN (1875 125) $PN 1
J 0
(1887 137);
DISPLAY 0.787234 (1887 137);
FORCEPROP 1 LASTPIN (2075 125) $PN 2
J 0
(2037 137);
DISPLAY 0.787234 (2037 137);
FORCEPROP 2 LAST CDS_LIB pure_quanta
J 0
(1975 125);
PAINT MONO (1975 125);
DISPLAY INVISIBLE (1975 125);
FORCEPROP 1 LAST PATH I48
J 0
(1925 275);
DISPLAY 0.978723 (1925 275);
PAINT WHITE (1925 275);
DISPLAY INVISIBLE (1925 275);
FORCEPROP 2 LAST CDS_LOCATION R3729
J 0
(1925 325);
DISPLAY 1.021277 (1925 325);
DISPLAY INVISIBLE (1925 325);
FORCEPROP 2 LAST $SEC 1
J 0
(1925 325);
DISPLAY 0.680851 (1925 325);
PAINT MONO (1925 325);
DISPLAY INVISIBLE (1925 325);
FORCEPROP 2 LAST CDS_SEC 1
J 0
(1925 325);
DISPLAY 1.021277 (1925 325);
DISPLAY INVISIBLE (1925 325);
FORCEADD Q_RES..1
(1975 75);
FORCEPROP 1 LAST PART_NUMBER CS22202JB07
J 0
(1875 125);
DISPLAY 0.510638 (1875 125);
DISPLAY INVISIBLE (1875 125);
FORCEPROP 1 LAST TOLERANCE 5%
J 0
(2200 75);
DISPLAY 0.510638 (2200 75);
FORCEPROP 1 LAST MATERIAL CHIP
J 0
(2275 75);
DISPLAY 0.510638 (2275 75);
FORCEPROP 1 LAST VALUE 2.2K
J 2
(2200 75);
DISPLAY 0.510638 (2200 75);
FORCEPROP 1 LAST $LOCATION R3730
J 0
(1725 75);
DISPLAY 0.510638 (1725 75);
FORCEPROP 1 LASTPIN (1875 75) $PN 1
J 0
(1887 87);
DISPLAY 0.787234 (1887 87);
FORCEPROP 1 LASTPIN (2075 75) $PN 2
J 0
(2037 87);
DISPLAY 0.787234 (2037 87);
FORCEPROP 1 LAST WATTAGE 1/16W
J 2
(2175 175);
DISPLAY 0.510638 (2175 175);
DISPLAY INVISIBLE (2175 175);
FORCEPROP 1 LAST PACK_TYPE 0402LF
J 0
(1875 175);
DISPLAY 0.510638 (1875 175);
DISPLAY INVISIBLE (1875 175);
FORCEPROP 2 LAST CDS_LIB pure_quanta
J 0
(1975 75);
PAINT MONO (1975 75);
DISPLAY INVISIBLE (1975 75);
FORCEPROP 1 LAST PATH I49
J 0
(1925 225);
DISPLAY 0.978723 (1925 225);
PAINT WHITE (1925 225);
DISPLAY INVISIBLE (1925 225);
FORCEPROP 2 LAST CDS_LOCATION R3730
J 0
(1925 275);
DISPLAY 1.021277 (1925 275);
DISPLAY INVISIBLE (1925 275);
FORCEPROP 2 LAST $SEC 1
J 0
(1925 275);
DISPLAY 0.680851 (1925 275);
PAINT MONO (1925 275);
DISPLAY INVISIBLE (1925 275);
FORCEPROP 2 LAST CDS_SEC 1
J 0
(1925 275);
DISPLAY 1.021277 (1925 275);
DISPLAY INVISIBLE (1925 275);
FORCEADD UNIVERSAL_GND..1
(-2875 -150);
FORCEPROP 3 LASTPIN (-2875 -100) SIG_NAME GND\g
J 0
(-2865 -90);
DISPLAY 0.659574 (-2865 -90);
PAINT MONO (-2865 -90);
DISPLAY INVISIBLE (-2865 -90);
FORCEPROP 2 LAST CDS_LIB logical_power
J 0
(-2875 -150);
PAINT MONO (-2875 -150);
DISPLAY INVISIBLE (-2875 -150);
FORCEPROP 2 LAST ROOM IO_SLOT
J 1
(-3100 -75);
DISPLAY 0.744681 (-3100 -75);
DISPLAY INVISIBLE (-3100 -75);
FORCEPROP 1 LAST HDL_POWER GND
J 1
(-2850 -225);
DISPLAY 0.872340 (-2850 -225);
PAINT GREEN (-2850 -225);
DISPLAY INVISIBLE (-2850 -225);
FORCEPROP 1 LAST PATH I5
J 0
(-2800 -150);
DISPLAY 0.872340 (-2800 -150);
PAINT AQUA (-2800 -150);
DISPLAY INVISIBLE (-2800 -150);
FORCEADD Q_RES..1
(1950 375);
FORCEPROP 1 LAST PART_NUMBER CS22202JB07
J 0
(1850 425);
DISPLAY 0.510638 (1850 425);
DISPLAY INVISIBLE (1850 425);
FORCEPROP 1 LAST TOLERANCE 5%
J 0
(2225 375);
DISPLAY 0.638298 (2225 375);
FORCEPROP 1 LAST MATERIAL CHIP
J 0
(2325 375);
DISPLAY 0.638298 (2325 375);
FORCEPROP 1 LAST VALUE 2.2K
J 2
(2225 375);
DISPLAY 0.638298 (2225 375);
FORCEPROP 1 LAST $LOCATION R3728
J 0
(1700 375);
DISPLAY 0.510638 (1700 375);
FORCEPROP 1 LAST WATTAGE 1/16W
J 2
(2150 475);
DISPLAY 0.510638 (2150 475);
DISPLAY INVISIBLE (2150 475);
FORCEPROP 1 LAST PACK_TYPE 0402LF
J 0
(1850 475);
DISPLAY 0.510638 (1850 475);
DISPLAY INVISIBLE (1850 475);
FORCEPROP 2 LAST CDS_LIB pure_quanta
J 0
(1950 375);
DISPLAY INVISIBLE (1950 375);
FORCEPROP 1 LAST PATH I50
J 0
(1900 525);
DISPLAY 0.978723 (1900 525);
PAINT WHITE (1900 525);
DISPLAY INVISIBLE (1900 525);
FORCEPROP 0 LAST CDS_LOCATION R3728
J 0
(2325 425);
DISPLAY INVISIBLE (2325 425);
FORCEPROP 0 LAST $SEC 1
J 0
(2325 425);
DISPLAY INVISIBLE (2325 425);
FORCEPROP 0 LAST CDS_SEC 1
J 0
(2325 425);
DISPLAY INVISIBLE (2325 425);
FORCEPROP 1 LASTPIN (1850 375) $PN 1
J 0
(1862 387);
DISPLAY 0.787234 (1862 387);
PAINT MONO (1862 387);
DISPLAY INVISIBLE (1862 387);
FORCEPROP 1 LASTPIN (2050 375) $PN 2
J 0
(2012 387);
DISPLAY 0.787234 (2012 387);
PAINT MONO (2012 387);
DISPLAY INVISIBLE (2012 387);
FORCEADD Q_RES..1
(1950 425);
FORCEPROP 1 LAST PART_NUMBER CS22202JB07
J 0
(1800 500);
DISPLAY 0.510638 (1800 500);
DISPLAY INVISIBLE (1800 500);
FORCEPROP 1 LAST TOLERANCE 5%
J 0
(2225 425);
DISPLAY 0.638298 (2225 425);
FORCEPROP 1 LAST VALUE 2.2K
J 2
(2225 425);
DISPLAY 0.638298 (2225 425);
FORCEPROP 1 LAST WATTAGE 1/16W
J 2
(2100 550);
DISPLAY 0.510638 (2100 550);
FORCEPROP 1 LAST MATERIAL CHIP
J 0
(2325 425);
DISPLAY 0.638298 (2325 425);
FORCEPROP 1 LAST PACK_TYPE 0402LF
J 0
(1800 550);
DISPLAY 0.510638 (1800 550);
FORCEPROP 1 LAST $LOCATION R3727
J 0
(1700 425);
DISPLAY 0.510638 (1700 425);
FORCEPROP 2 LAST CDS_LIB pure_quanta
J 0
(1950 425);
DISPLAY INVISIBLE (1950 425);
FORCEPROP 1 LAST PATH I51
J 0
(1900 575);
DISPLAY 0.978723 (1900 575);
PAINT WHITE (1900 575);
DISPLAY INVISIBLE (1900 575);
FORCEPROP 0 LAST CDS_LOCATION R3727
J 0
(2100 575);
DISPLAY INVISIBLE (2100 575);
FORCEPROP 0 LAST $SEC 1
J 0
(2100 575);
DISPLAY INVISIBLE (2100 575);
FORCEPROP 0 LAST CDS_SEC 1
J 0
(2100 575);
DISPLAY INVISIBLE (2100 575);
FORCEPROP 1 LASTPIN (1850 425) $PN 1
J 0
(1862 437);
DISPLAY 0.787234 (1862 437);
PAINT MONO (1862 437);
DISPLAY INVISIBLE (1862 437);
FORCEPROP 1 LASTPIN (2050 425) $PN 2
J 0
(2012 437);
DISPLAY 0.787234 (2012 437);
PAINT MONO (2012 437);
DISPLAY INVISIBLE (2012 437);
FORCEADD Q_RES..1
(1950 650);
FORCEPROP 1 LAST PART_NUMBER CS22202JB07
J 0
(1850 700);
DISPLAY 0.510638 (1850 700);
DISPLAY INVISIBLE (1850 700);
FORCEPROP 1 LAST MATERIAL CHIP
J 0
(2325 650);
DISPLAY 0.638298 (2325 650);
FORCEPROP 1 LAST VALUE 2.2K
J 2
(2225 650);
DISPLAY 0.638298 (2225 650);
FORCEPROP 1 LAST TOLERANCE 5%
J 0
(2225 650);
DISPLAY 0.638298 (2225 650);
FORCEPROP 1 LAST $LOCATION R3726
J 0
(1700 650);
DISPLAY 0.510638 (1700 650);
FORCEPROP 2 LAST CDS_LIB pure_quanta
J 0
(1950 650);
DISPLAY INVISIBLE (1950 650);
FORCEPROP 1 LAST PACK_TYPE 0402LF
J 0
(1850 750);
DISPLAY 0.510638 (1850 750);
DISPLAY INVISIBLE (1850 750);
FORCEPROP 1 LAST WATTAGE 1/16W
J 2
(2150 750);
DISPLAY 0.510638 (2150 750);
DISPLAY INVISIBLE (2150 750);
FORCEPROP 1 LAST PATH I52
J 0
(1900 800);
DISPLAY 0.978723 (1900 800);
PAINT WHITE (1900 800);
DISPLAY INVISIBLE (1900 800);
FORCEPROP 0 LAST CDS_LOCATION R3726
J 0
(2325 700);
DISPLAY INVISIBLE (2325 700);
FORCEPROP 0 LAST $SEC 1
J 0
(2325 700);
DISPLAY INVISIBLE (2325 700);
FORCEPROP 0 LAST CDS_SEC 1
J 0
(2325 700);
DISPLAY INVISIBLE (2325 700);
FORCEPROP 1 LASTPIN (1850 650) $PN 1
J 0
(1862 662);
DISPLAY 0.787234 (1862 662);
PAINT MONO (1862 662);
DISPLAY INVISIBLE (1862 662);
FORCEPROP 1 LASTPIN (2050 650) $PN 2
J 0
(2012 662);
DISPLAY 0.787234 (2012 662);
PAINT MONO (2012 662);
DISPLAY INVISIBLE (2012 662);
FORCEADD Q_RES..1
(1950 700);
FORCEPROP 1 LAST PART_NUMBER CS22202JB07
J 0
(1800 775);
DISPLAY 0.510638 (1800 775);
DISPLAY INVISIBLE (1800 775);
FORCEPROP 1 LAST MATERIAL CHIP
J 0
(2325 700);
DISPLAY 0.638298 (2325 700);
FORCEPROP 1 LAST PACK_TYPE 0402LF
J 0
(1800 825);
DISPLAY 0.510638 (1800 825);
FORCEPROP 1 LAST TOLERANCE 5%
J 0
(2225 700);
DISPLAY 0.638298 (2225 700);
FORCEPROP 1 LAST WATTAGE 1/16W
J 2
(2100 825);
DISPLAY 0.510638 (2100 825);
FORCEPROP 1 LAST VALUE 2.2K
J 2
(2225 700);
DISPLAY 0.638298 (2225 700);
FORCEPROP 1 LAST $LOCATION R3725
J 0
(1700 700);
DISPLAY 0.510638 (1700 700);
FORCEPROP 2 LAST CDS_LIB pure_quanta
J 0
(1950 700);
DISPLAY INVISIBLE (1950 700);
FORCEPROP 1 LAST PATH I53
J 0
(1900 850);
DISPLAY 0.978723 (1900 850);
PAINT WHITE (1900 850);
DISPLAY INVISIBLE (1900 850);
FORCEPROP 0 LAST CDS_LOCATION R3725
J 0
(2100 850);
DISPLAY INVISIBLE (2100 850);
FORCEPROP 0 LAST $SEC 1
J 0
(2100 850);
DISPLAY INVISIBLE (2100 850);
FORCEPROP 0 LAST CDS_SEC 1
J 0
(2100 850);
DISPLAY INVISIBLE (2100 850);
FORCEPROP 1 LASTPIN (1850 700) $PN 1
J 0
(1862 712);
DISPLAY 0.787234 (1862 712);
PAINT MONO (1862 712);
DISPLAY INVISIBLE (1862 712);
FORCEPROP 1 LASTPIN (2050 700) $PN 2
J 0
(2012 712);
DISPLAY 0.787234 (2012 712);
PAINT MONO (2012 712);
DISPLAY INVISIBLE (2012 712);
FORCEADD UNIVERSAL_POWER..1
(1525 1275);
FORCEPROP 3 LASTPIN (1525 1225) SIG_NAME P3V3_AUX\g
J 0
(1535 1235);
DISPLAY 0.659574 (1535 1235);
PAINT MONO (1535 1235);
DISPLAY INVISIBLE (1535 1235);
FORCEPROP 1 LAST HDL_POWER P3V3_AUX
J 1
(1525 1325);
DISPLAY 0.872340 (1525 1325);
PAINT GREEN (1525 1325);
FORCEPROP 2 LAST CDS_LIB logical_power
J 0
(1525 1275);
PAINT MONO (1525 1275);
DISPLAY INVISIBLE (1525 1275);
FORCEPROP 1 LAST PATH I54
J 0
(1575 1300);
DISPLAY 0.872340 (1575 1300);
PAINT AQUA (1575 1300);
DISPLAY INVISIBLE (1575 1300);
FORCEADD Q_RES..1
(1950 1075);
FORCEPROP 1 LAST PART_NUMBER CS22202JB07
J 0
(1800 1150);
DISPLAY 0.510638 (1800 1150);
DISPLAY INVISIBLE (1800 1150);
FORCEPROP 1 LAST PACK_TYPE 0402LF
J 0
(1800 1200);
DISPLAY 0.510638 (1800 1200);
FORCEPROP 1 LAST MATERIAL CHIP
J 0
(2325 1075);
DISPLAY 0.638298 (2325 1075);
FORCEPROP 1 LAST TOLERANCE 5%
J 0
(2225 1075);
DISPLAY 0.638298 (2225 1075);
FORCEPROP 1 LAST WATTAGE 1/16W
J 2
(2100 1200);
DISPLAY 0.510638 (2100 1200);
FORCEPROP 1 LAST VALUE 2.2K
J 2
(2225 1075);
DISPLAY 0.638298 (2225 1075);
FORCEPROP 1 LAST $LOCATION R3723
J 0
(1700 1075);
DISPLAY 0.510638 (1700 1075);
FORCEPROP 2 LAST CDS_LIB pure_quanta
J 0
(1950 1075);
DISPLAY INVISIBLE (1950 1075);
FORCEPROP 1 LAST PATH I55
J 0
(1900 1225);
DISPLAY 0.978723 (1900 1225);
PAINT WHITE (1900 1225);
DISPLAY INVISIBLE (1900 1225);
FORCEPROP 0 LAST CDS_LOCATION R3723
J 0
(2100 1225);
DISPLAY INVISIBLE (2100 1225);
FORCEPROP 0 LAST $SEC 1
J 0
(2100 1225);
DISPLAY INVISIBLE (2100 1225);
FORCEPROP 0 LAST CDS_SEC 1
J 0
(2100 1225);
DISPLAY INVISIBLE (2100 1225);
FORCEPROP 1 LASTPIN (1850 1075) $PN 1
J 0
(1862 1087);
DISPLAY 0.787234 (1862 1087);
PAINT MONO (1862 1087);
DISPLAY INVISIBLE (1862 1087);
FORCEPROP 1 LASTPIN (2050 1075) $PN 2
J 0
(2012 1087);
DISPLAY 0.787234 (2012 1087);
PAINT MONO (2012 1087);
DISPLAY INVISIBLE (2012 1087);
FORCEADD Q_RES..1
(1950 1025);
FORCEPROP 1 LAST PART_NUMBER CS22202JB07
J 0
(1850 1075);
DISPLAY 0.510638 (1850 1075);
DISPLAY INVISIBLE (1850 1075);
FORCEPROP 1 LAST TOLERANCE 5%
J 0
(2225 1025);
DISPLAY 0.638298 (2225 1025);
FORCEPROP 1 LAST MATERIAL CHIP
J 0
(2325 1025);
DISPLAY 0.638298 (2325 1025);
FORCEPROP 1 LAST VALUE 2.2K
J 2
(2225 1025);
DISPLAY 0.638298 (2225 1025);
FORCEPROP 1 LAST $LOCATION R3724
J 0
(1700 1025);
DISPLAY 0.510638 (1700 1025);
FORCEPROP 2 LAST CDS_LIB pure_quanta
J 0
(1950 1025);
DISPLAY INVISIBLE (1950 1025);
FORCEPROP 1 LAST PACK_TYPE 0402LF
J 0
(1850 1125);
DISPLAY 0.510638 (1850 1125);
DISPLAY INVISIBLE (1850 1125);
FORCEPROP 1 LAST WATTAGE 1/16W
J 2
(2150 1125);
DISPLAY 0.510638 (2150 1125);
DISPLAY INVISIBLE (2150 1125);
FORCEPROP 1 LAST PATH I56
J 0
(1900 1175);
DISPLAY 0.978723 (1900 1175);
PAINT WHITE (1900 1175);
DISPLAY INVISIBLE (1900 1175);
FORCEPROP 0 LAST CDS_LOCATION R3724
J 0
(2325 1075);
DISPLAY INVISIBLE (2325 1075);
FORCEPROP 0 LAST $SEC 1
J 0
(2325 1075);
DISPLAY INVISIBLE (2325 1075);
FORCEPROP 0 LAST CDS_SEC 1
J 0
(2325 1075);
DISPLAY INVISIBLE (2325 1075);
FORCEPROP 1 LASTPIN (1850 1025) $PN 1
J 0
(1862 1037);
DISPLAY 0.787234 (1862 1037);
PAINT MONO (1862 1037);
DISPLAY INVISIBLE (1862 1037);
FORCEPROP 1 LASTPIN (2050 1025) $PN 2
J 0
(2012 1037);
DISPLAY 0.787234 (2012 1037);
PAINT MONO (2012 1037);
DISPLAY INVISIBLE (2012 1037);
FORCEADD Q_RES..2
(-2875 75);
FORCEPROP 1 LAST PART_NUMBER CS21002FB06
J 0
(-2835 -50);
DISPLAY 0.510638 (-2835 -50);
DISPLAY INVISIBLE (-2835 -50);
FORCEPROP 1 LAST PACK_TYPE 0402LF
J 0
(-2835 -50);
DISPLAY 0.638298 (-2835 -50);
FORCEPROP 1 LAST VALUE 1K
J 0
(-2830 150);
DISPLAY 0.638298 (-2830 150);
FORCEPROP 1 LAST MATERIAL CHIP
J 0
(-2835 0);
DISPLAY 0.638298 (-2835 0);
FORCEPROP 1 LAST WATTAGE 1/16W
J 0
(-2835 50);
DISPLAY 0.638298 (-2835 50);
FORCEPROP 1 LAST TOLERANCE 1%
J 0
(-2830 100);
DISPLAY 0.638298 (-2830 100);
FORCEPROP 1 LAST $LOCATION R3707
J 0
(-2830 200);
DISPLAY 0.978723 (-2830 200);
FORCEPROP 1 LASTPIN (-2875 175) $PN 1
J 0
(-2870 137);
DISPLAY 0.787234 (-2870 137);
FORCEPROP 1 LASTPIN (-2875 -25) $PN 2
J 0
(-2870 -15);
DISPLAY 0.787234 (-2870 -15);
FORCEPROP 2 LAST CDS_LIB pure_quanta
J 0
(-2875 75);
PAINT MONO (-2875 75);
DISPLAY INVISIBLE (-2875 75);
FORCEPROP 1 LAST PATH I6
J 0
(-2825 250);
DISPLAY 0.978723 (-2825 250);
PAINT WHITE (-2825 250);
DISPLAY INVISIBLE (-2825 250);
FORCEPROP 2 LAST CDS_LOCATION R3707
J 0
(-2825 300);
DISPLAY 1.021277 (-2825 300);
DISPLAY INVISIBLE (-2825 300);
FORCEPROP 2 LAST $SEC 1
J 0
(-2825 300);
DISPLAY 0.680851 (-2825 300);
PAINT MONO (-2825 300);
DISPLAY INVISIBLE (-2825 300);
FORCEPROP 2 LAST CDS_SEC 1
J 0
(-2825 300);
DISPLAY 1.021277 (-2825 300);
DISPLAY INVISIBLE (-2825 300);
FORCEADD UNIVERSAL_GND..1
(-2600 -150);
FORCEPROP 3 LASTPIN (-2600 -100) SIG_NAME GND\g
J 0
(-2590 -90);
DISPLAY 0.659574 (-2590 -90);
PAINT MONO (-2590 -90);
DISPLAY INVISIBLE (-2590 -90);
FORCEPROP 2 LAST CDS_LIB logical_power
J 0
(-2600 -150);
PAINT MONO (-2600 -150);
DISPLAY INVISIBLE (-2600 -150);
FORCEPROP 2 LAST ROOM IO_SLOT
J 1
(-2825 -75);
DISPLAY 0.744681 (-2825 -75);
DISPLAY INVISIBLE (-2825 -75);
FORCEPROP 1 LAST HDL_POWER GND
J 1
(-2575 -225);
DISPLAY 0.872340 (-2575 -225);
PAINT GREEN (-2575 -225);
DISPLAY INVISIBLE (-2575 -225);
FORCEPROP 1 LAST PATH I7
J 0
(-2525 -150);
DISPLAY 0.872340 (-2525 -150);
PAINT AQUA (-2525 -150);
DISPLAY INVISIBLE (-2525 -150);
FORCEADD OFFPAGE..2
(3375 -175);
FORCEPROP 2 LAST $XR1 233 
J 0
(3684 -175);
DISPLAY 0.638298 (3684 -175);
PAINT MONO (3684 -175);
FORCEPROP 2 LAST $XR0 170 
J 0
(3564 -175);
DISPLAY 0.638298 (3564 -175);
PAINT MONO (3564 -175);
FORCEPROP 2 LAST CDS_LIB standard
J 0
(3375 -175);
PAINT MONO (3375 -175);
DISPLAY INVISIBLE (3375 -175);
FORCEPROP 1 LAST OFFPAGE TRUE
J 0
(3700 -300);
DISPLAY 0.872340 (3700 -300);
PAINT GREEN (3700 -300);
DISPLAY INVISIBLE (3700 -300);
FORCEPROP 1 LAST COMMENT_BODY TRUE
J 0
(3330 -270);
DISPLAY 0.872340 (3330 -270);
PAINT GREEN (3330 -270);
DISPLAY INVISIBLE (3330 -270);
FORCEPROP 2 LAST PATH I75
J 0
(3700 -125);
DISPLAY 1.021277 (3700 -125);
DISPLAY INVISIBLE (3700 -125);
FORCEADD OFFPAGE..2
(3375 75);
FORCEPROP 2 LAST $XR1 170 
J 0
(3684 75);
DISPLAY 0.638298 (3684 75);
PAINT MONO (3684 75);
FORCEPROP 2 LAST $XR0 233 
J 0
(3564 75);
DISPLAY 0.638298 (3564 75);
PAINT MONO (3564 75);
FORCEPROP 2 LAST CDS_LIB standard
J 0
(3375 75);
PAINT MONO (3375 75);
DISPLAY INVISIBLE (3375 75);
FORCEPROP 1 LAST OFFPAGE TRUE
J 0
(3700 -50);
DISPLAY 0.872340 (3700 -50);
PAINT GREEN (3700 -50);
DISPLAY INVISIBLE (3700 -50);
FORCEPROP 1 LAST COMMENT_BODY TRUE
J 0
(3330 -20);
DISPLAY 0.872340 (3330 -20);
PAINT GREEN (3330 -20);
DISPLAY INVISIBLE (3330 -20);
FORCEPROP 2 LAST PATH I76
J 0
(3700 125);
DISPLAY 1.021277 (3700 125);
DISPLAY INVISIBLE (3700 125);
FORCEADD OFFPAGE..2
(3375 125);
FORCEPROP 2 LAST $XR1 233 
J 0
(3684 125);
DISPLAY 0.638298 (3684 125);
PAINT MONO (3684 125);
FORCEPROP 2 LAST $XR0 170 
J 0
(3564 125);
DISPLAY 0.638298 (3564 125);
PAINT MONO (3564 125);
FORCEPROP 2 LAST CDS_LIB standard
J 0
(3375 125);
PAINT MONO (3375 125);
DISPLAY INVISIBLE (3375 125);
FORCEPROP 1 LAST OFFPAGE TRUE
J 0
(3700 0);
DISPLAY 0.872340 (3700 0);
PAINT GREEN (3700 0);
DISPLAY INVISIBLE (3700 0);
FORCEPROP 1 LAST COMMENT_BODY TRUE
J 0
(3330 30);
DISPLAY 0.872340 (3330 30);
PAINT GREEN (3330 30);
DISPLAY INVISIBLE (3330 30);
FORCEPROP 2 LAST PATH I77
J 0
(3700 175);
DISPLAY 1.021277 (3700 175);
DISPLAY INVISIBLE (3700 175);
FORCEADD OFFPAGE..2
(3350 375);
FORCEPROP 2 LAST $XR1 170 
J 0
(3659 375);
DISPLAY 0.638298 (3659 375);
PAINT MONO (3659 375);
FORCEPROP 2 LAST $XR0 233 
J 0
(3539 375);
DISPLAY 0.638298 (3539 375);
PAINT MONO (3539 375);
FORCEPROP 2 LAST CDS_LIB standard
J 0
(3350 375);
PAINT MONO (3350 375);
DISPLAY INVISIBLE (3350 375);
FORCEPROP 1 LAST OFFPAGE TRUE
J 0
(3675 250);
DISPLAY 0.872340 (3675 250);
PAINT GREEN (3675 250);
DISPLAY INVISIBLE (3675 250);
FORCEPROP 1 LAST COMMENT_BODY TRUE
J 0
(3305 280);
DISPLAY 0.872340 (3305 280);
PAINT GREEN (3305 280);
DISPLAY INVISIBLE (3305 280);
FORCEPROP 2 LAST PATH I78
J 0
(3675 425);
DISPLAY 1.021277 (3675 425);
DISPLAY INVISIBLE (3675 425);
FORCEADD OFFPAGE..2
(3350 425);
FORCEPROP 2 LAST $XR1 233 
J 0
(3659 425);
DISPLAY 0.638298 (3659 425);
PAINT MONO (3659 425);
FORCEPROP 2 LAST $XR0 170 
J 0
(3539 425);
DISPLAY 0.638298 (3539 425);
PAINT MONO (3539 425);
FORCEPROP 2 LAST CDS_LIB standard
J 0
(3350 425);
PAINT MONO (3350 425);
DISPLAY INVISIBLE (3350 425);
FORCEPROP 1 LAST OFFPAGE TRUE
J 0
(3675 300);
DISPLAY 0.872340 (3675 300);
PAINT GREEN (3675 300);
DISPLAY INVISIBLE (3675 300);
FORCEPROP 1 LAST COMMENT_BODY TRUE
J 0
(3305 330);
DISPLAY 0.872340 (3305 330);
PAINT GREEN (3305 330);
DISPLAY INVISIBLE (3305 330);
FORCEPROP 2 LAST PATH I79
J 0
(3675 475);
DISPLAY 1.021277 (3675 475);
DISPLAY INVISIBLE (3675 475);
FORCEADD Q_RES..2
(-2600 75);
FORCEPROP 1 LAST PART_NUMBER CS21002FB06
J 0
(-2560 -50);
DISPLAY 0.510638 (-2560 -50);
DISPLAY INVISIBLE (-2560 -50);
FORCEPROP 1 LAST PACK_TYPE 0402LF
J 0
(-2560 -100);
DISPLAY 0.638298 (-2560 -100);
FORCEPROP 1 LAST WATTAGE 1/16W
J 0
(-2560 50);
DISPLAY 0.638298 (-2560 50);
FORCEPROP 1 LAST MATERIAL CHIP
J 0
(-2560 0);
DISPLAY 0.638298 (-2560 0);
FORCEPROP 1 LAST VALUE 1K
J 0
(-2555 150);
DISPLAY 0.638298 (-2555 150);
FORCEPROP 1 LAST TOLERANCE 1%
J 0
(-2555 100);
DISPLAY 0.638298 (-2555 100);
FORCEPROP 1 LAST $LOCATION R3709
J 0
(-2555 200);
DISPLAY 0.978723 (-2555 200);
FORCEPROP 1 LASTPIN (-2600 175) $PN 1
J 0
(-2595 137);
DISPLAY 0.787234 (-2595 137);
FORCEPROP 1 LASTPIN (-2600 -25) $PN 2
J 0
(-2595 -15);
DISPLAY 0.787234 (-2595 -15);
FORCEPROP 2 LAST CDS_LIB pure_quanta
J 0
(-2600 75);
PAINT MONO (-2600 75);
DISPLAY INVISIBLE (-2600 75);
FORCEPROP 1 LAST PATH I8
J 0
(-2550 250);
DISPLAY 0.978723 (-2550 250);
PAINT WHITE (-2550 250);
DISPLAY INVISIBLE (-2550 250);
FORCEPROP 2 LAST CDS_LOCATION R3709
J 0
(-2550 300);
DISPLAY 1.021277 (-2550 300);
DISPLAY INVISIBLE (-2550 300);
FORCEPROP 2 LAST $SEC 1
J 0
(-2550 300);
DISPLAY 0.680851 (-2550 300);
PAINT MONO (-2550 300);
DISPLAY INVISIBLE (-2550 300);
FORCEPROP 2 LAST CDS_SEC 1
J 0
(-2550 300);
DISPLAY 1.021277 (-2550 300);
DISPLAY INVISIBLE (-2550 300);
FORCEADD OFFPAGE..2
(3350 700);
FORCEPROP 2 LAST $XR3 305 
J 0
(3899 700);
DISPLAY 0.638298 (3899 700);
PAINT MONO (3899 700);
FORCEPROP 2 LAST $XR2 251 
J 0
(3779 700);
DISPLAY 0.638298 (3779 700);
PAINT MONO (3779 700);
FORCEPROP 2 LAST $XR1 233 
J 0
(3659 700);
DISPLAY 0.638298 (3659 700);
PAINT MONO (3659 700);
FORCEPROP 2 LAST $XR0 170 
J 0
(3539 700);
DISPLAY 0.638298 (3539 700);
PAINT MONO (3539 700);
FORCEPROP 2 LAST CDS_LIB standard
J 0
(3350 700);
PAINT MONO (3350 700);
DISPLAY INVISIBLE (3350 700);
FORCEPROP 1 LAST OFFPAGE TRUE
J 0
(3675 575);
DISPLAY 0.872340 (3675 575);
PAINT GREEN (3675 575);
DISPLAY INVISIBLE (3675 575);
FORCEPROP 1 LAST COMMENT_BODY TRUE
J 0
(3305 605);
DISPLAY 0.872340 (3305 605);
PAINT GREEN (3305 605);
DISPLAY INVISIBLE (3305 605);
FORCEPROP 2 LAST PATH I80
J 0
(3675 750);
DISPLAY 1.021277 (3675 750);
DISPLAY INVISIBLE (3675 750);
FORCEADD OFFPAGE..2
(3350 650);
FORCEPROP 2 LAST $XR3 170 
J 0
(3899 650);
DISPLAY 0.638298 (3899 650);
PAINT MONO (3899 650);
FORCEPROP 2 LAST $XR2 305 
J 0
(3779 650);
DISPLAY 0.638298 (3779 650);
PAINT MONO (3779 650);
FORCEPROP 2 LAST $XR1 251 
J 0
(3659 650);
DISPLAY 0.638298 (3659 650);
PAINT MONO (3659 650);
FORCEPROP 2 LAST $XR0 233 
J 0
(3539 650);
DISPLAY 0.638298 (3539 650);
PAINT MONO (3539 650);
FORCEPROP 2 LAST CDS_LIB standard
J 0
(3350 650);
PAINT MONO (3350 650);
DISPLAY INVISIBLE (3350 650);
FORCEPROP 1 LAST OFFPAGE TRUE
J 0
(3675 525);
DISPLAY 0.872340 (3675 525);
PAINT GREEN (3675 525);
DISPLAY INVISIBLE (3675 525);
FORCEPROP 1 LAST COMMENT_BODY TRUE
J 0
(3305 555);
DISPLAY 0.872340 (3305 555);
PAINT GREEN (3305 555);
DISPLAY INVISIBLE (3305 555);
FORCEPROP 2 LAST PATH I81
J 0
(3675 700);
DISPLAY 1.021277 (3675 700);
DISPLAY INVISIBLE (3675 700);
FORCEADD OFFPAGE..2
(3350 1025);
FORCEPROP 2 LAST $XR1 241 
J 0
(3659 1025);
DISPLAY 0.638298 (3659 1025);
PAINT MONO (3659 1025);
FORCEPROP 2 LAST $XR0 233 
J 0
(3539 1025);
DISPLAY 0.638298 (3539 1025);
PAINT MONO (3539 1025);
FORCEPROP 2 LAST CDS_LIB standard
J 0
(3350 1025);
PAINT MONO (3350 1025);
DISPLAY INVISIBLE (3350 1025);
FORCEPROP 1 LAST OFFPAGE TRUE
J 0
(3675 900);
DISPLAY 0.872340 (3675 900);
PAINT GREEN (3675 900);
DISPLAY INVISIBLE (3675 900);
FORCEPROP 1 LAST COMMENT_BODY TRUE
J 0
(3305 930);
DISPLAY 0.872340 (3305 930);
PAINT GREEN (3305 930);
DISPLAY INVISIBLE (3305 930);
FORCEPROP 2 LAST PATH I82
J 0
(3675 1075);
DISPLAY 1.021277 (3675 1075);
DISPLAY INVISIBLE (3675 1075);
FORCEADD OFFPAGE..2
(3350 1075);
FORCEPROP 2 LAST $XR1 241 
J 0
(3659 1075);
DISPLAY 0.638298 (3659 1075);
PAINT MONO (3659 1075);
FORCEPROP 2 LAST $XR0 233 
J 0
(3539 1075);
DISPLAY 0.638298 (3539 1075);
PAINT MONO (3539 1075);
FORCEPROP 2 LAST CDS_LIB standard
J 0
(3350 1075);
PAINT MONO (3350 1075);
DISPLAY INVISIBLE (3350 1075);
FORCEPROP 1 LAST OFFPAGE TRUE
J 0
(3675 950);
DISPLAY 0.872340 (3675 950);
PAINT GREEN (3675 950);
DISPLAY INVISIBLE (3675 950);
FORCEPROP 1 LAST COMMENT_BODY TRUE
J 0
(3305 980);
DISPLAY 0.872340 (3305 980);
PAINT GREEN (3305 980);
DISPLAY INVISIBLE (3305 980);
FORCEPROP 2 LAST PATH I83
J 0
(3675 1125);
DISPLAY 1.021277 (3675 1125);
DISPLAY INVISIBLE (3675 1125);
FORCEADD Q_RES..2
(-2875 725);
FORCEPROP 1 LAST PART_NUMBER CS31002FB08
J 0
(-2835 600);
DISPLAY 0.510638 (-2835 600);
DISPLAY INVISIBLE (-2835 600);
FORCEPROP 1 LAST PACK_TYPE 0402LF
J 0
(-2835 600);
DISPLAY 0.638298 (-2835 600);
FORCEPROP 1 LAST MATERIAL EMPTY
J 0
(-2835 650);
DISPLAY 0.638298 (-2835 650);
PAINT RED (-2835 650);
FORCEPROP 1 LAST TOLERANCE 1%
J 0
(-2830 750);
DISPLAY 0.638298 (-2830 750);
FORCEPROP 1 LAST WATTAGE 1/16W
J 0
(-2835 700);
DISPLAY 0.638298 (-2835 700);
FORCEPROP 1 LAST VALUE 10K
J 0
(-2830 800);
DISPLAY 0.638298 (-2830 800);
FORCEPROP 1 LAST $LOCATION R3706
J 0
(-2830 850);
DISPLAY 0.978723 (-2830 850);
FORCEPROP 1 LASTPIN (-2875 825) $PN 1
J 0
(-2870 787);
DISPLAY 0.787234 (-2870 787);
FORCEPROP 1 LASTPIN (-2875 625) $PN 2
J 0
(-2870 635);
DISPLAY 0.787234 (-2870 635);
FORCEPROP 2 LAST CDS_LIB pure_quanta
J 0
(-2875 725);
PAINT MONO (-2875 725);
DISPLAY INVISIBLE (-2875 725);
FORCEPROP 1 LAST PATH I9
J 0
(-2825 900);
DISPLAY 0.978723 (-2825 900);
PAINT WHITE (-2825 900);
DISPLAY INVISIBLE (-2825 900);
FORCEPROP 2 LAST CDS_LOCATION R3706
J 0
(-2825 950);
DISPLAY 1.021277 (-2825 950);
DISPLAY INVISIBLE (-2825 950);
FORCEPROP 2 LAST $SEC 1
J 0
(-2825 950);
DISPLAY 0.680851 (-2825 950);
PAINT MONO (-2825 950);
DISPLAY INVISIBLE (-2825 950);
FORCEPROP 2 LAST CDS_SEC 1
J 0
(-2825 950);
DISPLAY 1.021277 (-2825 950);
DISPLAY INVISIBLE (-2825 950);
FORCEADD Q_RES..1
(1975 -175);
FORCEPROP 1 LAST PART_NUMBER CS22202JB07
J 0
(1825 -100);
DISPLAY 0.510638 (1825 -100);
DISPLAY INVISIBLE (1825 -100);
FORCEPROP 1 LAST VALUE 2.2K
J 2
(2225 -175);
DISPLAY 0.510638 (2225 -175);
FORCEPROP 1 LAST PACK_TYPE 0402LF
J 0
(1825 -50);
DISPLAY 0.510638 (1825 -50);
FORCEPROP 1 LAST TOLERANCE 5%
J 0
(2225 -175);
DISPLAY 0.510638 (2225 -175);
FORCEPROP 1 LAST MATERIAL CHIP
J 0
(2325 -175);
DISPLAY 0.510638 (2325 -175);
FORCEPROP 1 LAST WATTAGE 1/16W
J 2
(2125 -50);
DISPLAY 0.510638 (2125 -50);
FORCEPROP 1 LAST $LOCATION R3731
J 0
(1725 -175);
DISPLAY 0.638298 (1725 -175);
FORCEPROP 1 LASTPIN (1875 -175) $PN 1
J 0
(1887 -163);
DISPLAY 0.787234 (1887 -163);
FORCEPROP 1 LASTPIN (2075 -175) $PN 2
J 0
(2037 -163);
DISPLAY 0.787234 (2037 -163);
FORCEPROP 2 LAST CDS_LIB pure_quanta
J 0
(1975 -175);
PAINT MONO (1975 -175);
DISPLAY INVISIBLE (1975 -175);
FORCEPROP 1 LAST PATH I98
J 0
(1925 -25);
DISPLAY 0.978723 (1925 -25);
PAINT WHITE (1925 -25);
DISPLAY INVISIBLE (1925 -25);
FORCEPROP 2 LAST CDS_LOCATION R3731
J 0
(1925 25);
DISPLAY 1.021277 (1925 25);
DISPLAY INVISIBLE (1925 25);
FORCEPROP 2 LAST $SEC 1
J 0
(1925 25);
DISPLAY 0.680851 (1925 25);
PAINT MONO (1925 25);
DISPLAY INVISIBLE (1925 25);
FORCEPROP 2 LAST CDS_SEC 1
J 0
(1925 25);
DISPLAY 1.021277 (1925 25);
DISPLAY INVISIBLE (1925 25);
FORCEADD Q_RES..1
(1975 -475);
FORCEPROP 1 LAST PART_NUMBER CS22202JB07
J 0
(1875 -425);
DISPLAY 0.510638 (1875 -425);
DISPLAY INVISIBLE (1875 -425);
FORCEPROP 1 LAST MATERIAL EMPTY
J 0
(2350 -475);
DISPLAY 0.638298 (2350 -475);
PAINT RED (2350 -475);
FORCEPROP 1 LAST VALUE 2.2K
J 2
(2250 -475);
DISPLAY 0.638298 (2250 -475);
FORCEPROP 1 LAST TOLERANCE 5%
J 0
(2250 -475);
DISPLAY 0.638298 (2250 -475);
FORCEPROP 1 LAST $LOCATION R4270
J 0
(1725 -475);
DISPLAY 0.510638 (1725 -475);
FORCEPROP 1 LAST WATTAGE 1/16W
J 2
(2175 -375);
DISPLAY 0.510638 (2175 -375);
DISPLAY INVISIBLE (2175 -375);
FORCEPROP 1 LAST PACK_TYPE 0402LF
J 0
(1875 -375);
DISPLAY 0.510638 (1875 -375);
DISPLAY INVISIBLE (1875 -375);
FORCEPROP 2 LAST CDS_LIB pure_quanta
J 0
(1975 -475);
DISPLAY INVISIBLE (1975 -475);
FORCEPROP 1 LAST PATH I99
J 0
(1925 -325);
DISPLAY 0.978723 (1925 -325);
PAINT WHITE (1925 -325);
DISPLAY INVISIBLE (1925 -325);
FORCEPROP 0 LAST CDS_LOCATION R4270
J 0
(2350 -425);
DISPLAY INVISIBLE (2350 -425);
FORCEPROP 0 LAST $SEC 1
J 0
(2350 -425);
DISPLAY INVISIBLE (2350 -425);
FORCEPROP 0 LAST CDS_SEC 1
J 0
(2350 -425);
DISPLAY INVISIBLE (2350 -425);
FORCEPROP 1 LASTPIN (1875 -475) $PN 1
J 0
(1887 -463);
DISPLAY 0.787234 (1887 -463);
PAINT MONO (1887 -463);
DISPLAY INVISIBLE (1887 -463);
FORCEPROP 1 LASTPIN (2075 -475) $PN 2
J 0
(2037 -463);
DISPLAY 0.787234 (2037 -463);
PAINT MONO (2037 -463);
DISPLAY INVISIBLE (2037 -463);
FORCEADD QUANTA_TITLE_BLOCK_C..1
(4550 -2075);
FORCEPROP 0 LAST CDS_CON_LAST_MODIFIED Fri Aug 25 14:03:57 2023
J 0
(2665 -2060);
PAINT MONO (2665 -2060);
DISPLAY INVISIBLE (2665 -2060);
FORCEPROP 2 LAST CUSTOM_TXT_CDS <XR_PAGE_TITLE>
J 0
(-3340 3175);
DISPLAY 0.638298 (-3340 3175);
PAINT PINK (-3340 3175);
DISPLAY INVISIBLE (-3340 3175);
FORCEPROP 2 LAST CUSTOM_TXT_CDS <CON_LAST_MODIFIED>
J 0
(2665 -2060);
DISPLAY 0.978723 (2665 -2060);
FORCEPROP 2 LAST CUSTOM_TXT_CDS <CON_PAGE_NUM> OF <CON_TOTAL_PAGES>
J 0
(4104 -2057);
DISPLAY 0.978723 (4104 -2057);
FORCEPROP 2 LAST CUSTOM_TXT_CDS <Q_REV>
J 0
(4366 -1972);
DISPLAY 1.212766 (4366 -1972);
FORCEPROP 2 LAST CUSTOM_TXT_CDS <Q_PROJ>
J 0
(2168 -1973);
DISPLAY 1.212766 (2168 -1973);
FORCEPROP 2 LAST CUSTOM_TXT_CDS <Q_NUMBER>
J 0
(3147 -1972);
DISPLAY 1.212766 (3147 -1972);
FORCEPROP 2 LAST CUSTOM_TXT_CDS <NAME_1>
J 0
(1375 -1900);
FORCEPROP 2 LAST CUSTOM_TXT_CDS <NAME_2>
J 0
(1375 -2025);
FORCEPROP 1 LAST Q_TITLE SMBUS - PCIE2  SMBUS
J 0
(-4716 -2049);
DISPLAY 2.446809 (-4716 -2049);
PAINT GREEN (-4716 -2049);
FORCEPROP 1 LAST Q_DEPT 
J 1
(787 -2026);
DISPLAY 1.957447 (787 -2026);
PAINT GREEN (787 -2026);
FORCEPROP 2 LAST CDS_XR_PAGE_TITLE CR-233 : @S9S_MB_2U_LIB.S9S_MB_2U(SCH_1):PAGE233
J 0
(-3340 3175);
DISPLAY 0.638298 (-3340 3175);
PAINT PINK (-3340 3175);
DISPLAY INVISIBLE (-3340 3175);
FORCEPROP 2 LAST CDS_LIB pure_quanta
J 0
(4550 -2075);
PAINT MONO (4550 -2075);
DISPLAY INVISIBLE (4550 -2075);
FORCEPROP 1 LAST CDS_LMAN_SYM_OUTLINE -9475,6775,100,-125
J 0
(4550 -2075);
DISPLAY 0.468085 (4550 -2075);
PAINT GREEN (4550 -2075);
DISPLAY INVISIBLE (4550 -2075);
FORCEPROP 2 LAST PAGE_BORDER TRUE
J 0
(-3340 3175);
DISPLAY 0.638298 (-3340 3175);
PAINT PINK (-3340 3175);
DISPLAY INVISIBLE (-3340 3175);
FORCEPROP 1 LAST COMMENT_BODY TRUE
J 0
(4562 -2088);
DISPLAY 0.978723 (4562 -2088);
PAINT GREEN (4562 -2088);
DISPLAY INVISIBLE (4562 -2088);
FORCEADD DNS..2
(-3145 695);
PAINT RED (-3145 695);
FORCEPROP 2 LAST CDS_LIB mstr_misc
J 0
(-3145 695);
PAINT MONO (-3145 695);
DISPLAY INVISIBLE (-3145 695);
FORCEPROP 1 LAST COMMENT_BODY TRUE
J 0
(-3145 695);
DISPLAY INVISIBLE (-3145 695);
FORCEADD DNS..2
(-2870 695);
PAINT RED (-2870 695);
FORCEPROP 2 LAST CDS_LIB mstr_misc
J 0
(-2870 695);
PAINT MONO (-2870 695);
DISPLAY INVISIBLE (-2870 695);
FORCEPROP 1 LAST COMMENT_BODY TRUE
J 0
(-2870 695);
DISPLAY INVISIBLE (-2870 695);
FORCEADD DNS..2
(-2595 695);
PAINT RED (-2595 695);
FORCEPROP 2 LAST CDS_LIB mstr_misc
J 0
(-2595 695);
PAINT MONO (-2595 695);
DISPLAY INVISIBLE (-2595 695);
FORCEPROP 1 LAST COMMENT_BODY TRUE
J 0
(-2595 695);
DISPLAY INVISIBLE (-2595 695);
FORCEADD DNS..2
(2000 -425);
PAINT RED (2000 -425);
FORCEPROP 2 LAST CDS_LIB mstr_misc
J 0
(2000 -425);
DISPLAY INVISIBLE (2000 -425);
FORCEPROP 1 LAST COMMENT_BODY TRUE
J 0
(2000 -425);
DISPLAY INVISIBLE (2000 -425);
FORCEADD DNS..2
(2000 -475);
PAINT RED (2000 -475);
FORCEPROP 2 LAST CDS_LIB mstr_misc
J 0
(2000 -475);
DISPLAY INVISIBLE (2000 -475);
FORCEPROP 1 LAST COMMENT_BODY TRUE
J 0
(2000 -475);
DISPLAY INVISIBLE (2000 -475);
FORCEADD DNS..2
(-2425 2975);
PAINT RED (-2425 2975);
FORCEPROP 2 LAST CDS_LIB mstr_misc
J 0
(-2425 2975);
DISPLAY INVISIBLE (-2425 2975);
FORCEPROP 1 LAST COMMENT_BODY TRUE
J 0
(-2425 2975);
DISPLAY INVISIBLE (-2425 2975);
WIRE 16 -1 (-2425 3225)(-2425 3100);
WIRE 16 -1 (-625 3550)(-625 3475);
WIRE 16 -1 (1525 1225)(1525 1075);
WIRE 16 -1 (-3150 975)(-3150 1050);
WIRE 16 -1 (-3150 975)(-2875 975);
WIRE 16 -1 (-3150 825)(-3150 975);
WIRE 16 -1 (-625 3175)(-625 3100);
WIRE 16 -1 (700 2100)(700 1975);
WIRE 16 -1 (700 2100)(600 2100);
WIRE 16 -1 (-2600 -100)(-2600 -25);
WIRE 16 -1 (-2875 -100)(-2875 -25);
WIRE 16 -1 (-3150 -100)(-3150 -25);
WIRE 16 2175 (1700 -275)(3000 -275);
WIRE 16 2175 (3000 -275)(3000 -600);
WIRE 16 2175 (1700 -275)(1700 -600);
WIRE 16 2175 (1700 -600)(3000 -600);
WIRE 16 -1 (3300 -475)(2075 -475);
FORCEPROP 0 LAST CDS_PHYS_NET_NAME SMB_PCIE0_3V3AUX_SDA
J 0
(2290 -427);
PAINT MONO (2290 -427);
DISPLAY INVISIBLE (2290 -427);
FORCEPROP 2 LAST SIG_NAME SMB_VR_SENSOR_3V3AUX_SDA
J 0
(2590 -465);
DISPLAY 0.510638 (2590 -465);
PAINT WHITE (2590 -465);
WIRE 16 -1 (3300 -425)(2075 -425);
FORCEPROP 0 LAST CDS_PHYS_NET_NAME SMB_PCIE0_3V3AUX_SCL
J 0
(2290 -377);
PAINT MONO (2290 -377);
DISPLAY INVISIBLE (2290 -377);
FORCEPROP 2 LAST SIG_NAME SMB_VR_SENSOR_3V3AUX_SCL
J 0
(2590 -415);
DISPLAY 0.510638 (2590 -415);
PAINT WHITE (2590 -415);
WIRE 16 -1 (1525 1075)(1850 1075);
WIRE 16 -1 (1525 1075)(1525 1025);
WIRE 16 -1 (1525 1025)(1850 1025);
WIRE 16 -1 (1525 700)(1850 700);
WIRE 16 -1 (1525 1025)(1525 700);
WIRE 16 -1 (1525 700)(1525 650);
WIRE 16 -1 (1525 650)(1850 650);
WIRE 16 -1 (1525 650)(1525 425);
WIRE 16 -1 (1525 425)(1850 425);
WIRE 16 -1 (1525 425)(1525 375);
WIRE 16 -1 (1525 375)(1850 375);
WIRE 16 -1 (1525 375)(1525 125);
WIRE 16 -1 (1525 125)(1875 125);
WIRE 16 -1 (1525 125)(1525 75);
WIRE 16 -1 (1525 75)(1875 75);
WIRE 16 -1 (1525 -175)(1875 -175);
WIRE 16 -1 (1525 75)(1525 -175);
WIRE 16 -1 (1525 -225)(1525 -175);
WIRE 16 -1 (1525 -225)(1875 -225);
WIRE 16 -1 (1525 -225)(1525 -425);
WIRE 16 -1 (1875 -425)(1525 -425);
WIRE 16 -1 (1525 -425)(1525 -475);
WIRE 16 -1 (1875 -475)(1525 -475);
WIRE 16 -1 (-2875 825)(-2875 975);
WIRE 16 -1 (-2875 975)(-2600 975);
WIRE 16 -1 (-2600 825)(-2600 975);
WIRE 16 -1 (3325 -225)(2075 -225);
FORCEPROP 0 LAST CDS_PHYS_NET_NAME SMB_2_PLD_3V3AUX_SDA
J 0
(2290 -177);
PAINT MONO (2290 -177);
DISPLAY INVISIBLE (2290 -177);
FORCEPROP 2 LAST SIG_NAME SMB_LM75_3_3V3AUX_SDA
J 0
(2590 -215);
DISPLAY 0.510638 (2590 -215);
PAINT WHITE (2590 -215);
WIRE 16 -1 (3325 -175)(2075 -175);
FORCEPROP 0 LAST CDS_PHYS_NET_NAME SMB_2_PLD_3V3AUX_SCL
J 0
(2290 -127);
PAINT MONO (2290 -127);
DISPLAY INVISIBLE (2290 -127);
FORCEPROP 2 LAST SIG_NAME SMB_LM75_3_3V3AUX_SCL
J 0
(2590 -165);
DISPLAY 0.510638 (2590 -165);
PAINT WHITE (2590 -165);
WIRE 16 -1 (-2900 2650)(-2425 2650);
FORCEPROP 0 LAST CDS_PHYS_NET_NAME RST_SMB_SWITCH_N
J 0
(-2860 2698);
PAINT MONO (-2860 2698);
DISPLAY INVISIBLE (-2860 2698);
FORCEPROP 2 LAST SIG_NAME RST_SMB_SWITCH_N
J 0
(-2885 2660);
DISPLAY 0.510638 (-2885 2660);
PAINT WHITE (-2885 2660);
WIRE 16 -1 (-1425 2650)(-2425 2650);
WIRE 16 -1 (-2425 2900)(-2425 2650);
WIRE 16 -1 (-975 2500)(-100 2500);
FORCEPROP 0 LAST CDS_PHYS_NET_NAME SMB_VR_3V3AUX_SCL_R6
J 0
(-935 2548);
PAINT MONO (-935 2548);
DISPLAY INVISIBLE (-935 2548);
FORCEPROP 2 LAST SIG_NAME SMB_VR_3V3AUX_SCL_R6
J 0
(-710 2510);
DISPLAY 0.510638 (-710 2510);
PAINT WHITE (-710 2510);
WIRE 16 -1 (-100 2450)(-975 2450);
FORCEPROP 0 LAST CDS_PHYS_NET_NAME SMB_LM75_0_3V3AUX_SDA_R
J 0
(-935 2498);
PAINT MONO (-935 2498);
DISPLAY INVISIBLE (-935 2498);
FORCEPROP 2 LAST SIG_NAME SMB_LM75_0_3V3AUX_SDA_R
J 0
(-710 2460);
DISPLAY 0.510638 (-710 2460);
PAINT WHITE (-710 2460);
WIRE 16 -1 (-250 2950)(-100 2950);
WIRE 16 -1 (-250 3475)(-250 2950);
WIRE 16 -1 (-625 3375)(-625 3475);
WIRE 16 -1 (-625 3475)(-250 3475);
WIRE 16 -1 (-100 2650)(-1225 2650);
FORCEPROP 0 LAST CDS_PHYS_NET_NAME PU_RST_SMB_PCIE2_N
J 0
(-1185 2698);
PAINT MONO (-1185 2698);
DISPLAY INVISIBLE (-1185 2698);
FORCEPROP 2 LAST SIG_NAME PU_RST_SMB_PCIE2_N
J 0
(-735 2660);
DISPLAY 0.510638 (-735 2660);
PAINT WHITE (-735 2660);
WIRE 16 -1 (-2225 2550)(-1175 2550);
FORCEPROP 0 LAST CDS_PHYS_NET_NAME SMB_VR_3V3AUX_SDA
J 0
(-2185 2598);
PAINT MONO (-2185 2598);
DISPLAY INVISIBLE (-2185 2598);
FORCEPROP 2 LAST SIG_NAME SMB_VR_3V3AUX_SDA
J 0
(-1885 2560);
DISPLAY 0.510638 (-1885 2560);
PAINT WHITE (-1885 2560);
WIRE 16 -1 (-2225 2500)(-1175 2500);
FORCEPROP 0 LAST CDS_PHYS_NET_NAME SMB_VR_3V3AUX_SCL
J 0
(-2160 2548);
PAINT MONO (-2160 2548);
DISPLAY INVISIBLE (-2160 2548);
FORCEPROP 2 LAST SIG_NAME SMB_VR_3V3AUX_SCL
J 0
(-1885 2510);
DISPLAY 0.510638 (-1885 2510);
PAINT WHITE (-1885 2510);
WIRE 16 -1 (-975 2200)(-100 2200);
FORCEPROP 0 LAST CDS_PHYS_NET_NAME SMB_LM75_2_3V3AUX_SCL_R
J 0
(-935 2248);
PAINT MONO (-935 2248);
DISPLAY INVISIBLE (-935 2248);
FORCEPROP 2 LAST SIG_NAME SMB_LM75_2_3V3AUX_SCL_R
J 0
(-710 2210);
DISPLAY 0.510638 (-710 2210);
PAINT WHITE (-710 2210);
WIRE 16 -1 (-975 2250)(-100 2250);
FORCEPROP 0 LAST CDS_PHYS_NET_NAME SMB_LM75_2_3V3AUX_SDA_R
J 0
(-935 2298);
PAINT MONO (-935 2298);
DISPLAY INVISIBLE (-935 2298);
FORCEPROP 2 LAST SIG_NAME SMB_LM75_2_3V3AUX_SDA_R
J 0
(-710 2260);
DISPLAY 0.510638 (-710 2260);
PAINT WHITE (-710 2260);
WIRE 16 -1 (-975 2300)(-100 2300);
FORCEPROP 0 LAST CDS_PHYS_NET_NAME SMB_LM75_1_3V3AUX_SCL_R
J 0
(-935 2348);
PAINT MONO (-935 2348);
DISPLAY INVISIBLE (-935 2348);
FORCEPROP 2 LAST SIG_NAME SMB_LM75_1_3V3AUX_SCL_R
J 0
(-710 2310);
DISPLAY 0.510638 (-710 2310);
PAINT WHITE (-710 2310);
WIRE 16 -1 (-975 2350)(-100 2350);
FORCEPROP 0 LAST CDS_PHYS_NET_NAME SMB_LM75_1_3V3AUX_SDA_R
J 0
(-935 2398);
PAINT MONO (-935 2398);
DISPLAY INVISIBLE (-935 2398);
FORCEPROP 2 LAST SIG_NAME SMB_LM75_1_3V3AUX_SDA_R
J 0
(-710 2360);
DISPLAY 0.510638 (-710 2360);
PAINT WHITE (-710 2360);
WIRE 16 -1 (-100 2400)(-975 2400);
FORCEPROP 0 LAST CDS_PHYS_NET_NAME SMB_LM75_0_3V3AUX_SCL_R
J 0
(-935 2448);
PAINT MONO (-935 2448);
DISPLAY INVISIBLE (-935 2448);
FORCEPROP 2 LAST SIG_NAME SMB_LM75_0_3V3AUX_SCL_R
J 0
(-710 2410);
DISPLAY 0.510638 (-710 2410);
PAINT WHITE (-710 2410);
WIRE 16 -1 (-975 2550)(-100 2550);
FORCEPROP 0 LAST CDS_PHYS_NET_NAME SMB_VR_3V3AUX_SDA_R6
J 0
(-935 2598);
PAINT MONO (-935 2598);
DISPLAY INVISIBLE (-935 2598);
FORCEPROP 2 LAST SIG_NAME SMB_VR_3V3AUX_SDA_R6
J 0
(-710 2560);
DISPLAY 0.510638 (-710 2560);
PAINT WHITE (-710 2560);
WIRE 16 -1 (-775 2850)(-100 2850);
FORCEPROP 2 LAST SIG_NAME PCA9548_PCIE0_ADDR0
J 0
(-735 2860);
DISPLAY 0.510638 (-735 2860);
PAINT WHITE (-735 2860);
WIRE 16 -1 (600 2500)(1475 2500);
FORCEPROP 0 LAST CDS_PHYS_NET_NAME SMB_LM75_3_3V3AUX_SCL_R
J 0
(640 2548);
PAINT MONO (640 2548);
DISPLAY INVISIBLE (640 2548);
FORCEPROP 2 LAST SIG_NAME SMB_LM75_3_3V3AUX_SCL_R
J 0
(715 2510);
DISPLAY 0.510638 (715 2510);
PAINT WHITE (715 2510);
WIRE 16 -1 (2725 2500)(1675 2500);
FORCEPROP 0 LAST CDS_PHYS_NET_NAME SMB_LM75_3_3V3AUX_SCL
J 0
(515 2548);
PAINT MONO (515 2548);
DISPLAY INVISIBLE (515 2548);
FORCEPROP 2 LAST SIG_NAME SMB_LM75_3_3V3AUX_SCL
J 0
(2015 2510);
DISPLAY 0.510638 (2015 2510);
PAINT WHITE (2015 2510);
WIRE 16 -1 (2725 2550)(1675 2550);
FORCEPROP 0 LAST CDS_PHYS_NET_NAME SMB_LM75_3_3V3AUX_SDA
J 0
(515 2598);
PAINT MONO (515 2598);
DISPLAY INVISIBLE (515 2598);
FORCEPROP 2 LAST SIG_NAME SMB_LM75_3_3V3AUX_SDA
J 0
(2015 2560);
DISPLAY 0.510638 (2015 2560);
PAINT WHITE (2015 2560);
WIRE 16 -1 (1800 2800)(2700 2800);
FORCEPROP 0 LAST CDS_PHYS_NET_NAME SMB_VR_SENSOR_3V3AUX_SDA
J 0
(1840 2848);
PAINT MONO (1840 2848);
DISPLAY INVISIBLE (1840 2848);
FORCEPROP 2 LAST SIG_NAME SMB_VR_SENSOR_3V3AUX_SDA
J 0
(2015 2810);
DISPLAY 0.510638 (2015 2810);
PAINT WHITE (2015 2810);
WIRE 16 -1 (1800 2750)(2700 2750);
FORCEPROP 0 LAST CDS_PHYS_NET_NAME SMB_VR_SENSOR_3V3AUX_SCL
J 0
(1840 2798);
PAINT MONO (1840 2798);
DISPLAY INVISIBLE (1840 2798);
FORCEPROP 2 LAST SIG_NAME SMB_VR_SENSOR_3V3AUX_SCL
J 0
(2015 2760);
DISPLAY 0.510638 (2015 2760);
PAINT WHITE (2015 2760);
WIRE 16 -1 (600 2800)(1600 2800);
FORCEPROP 0 LAST CDS_PHYS_NET_NAME SMB_VR_SENSOR_3V3AUX_SDA_R
J 0
(640 2848);
PAINT MONO (640 2848);
DISPLAY INVISIBLE (640 2848);
FORCEPROP 2 LAST SIG_NAME SMB_VR_SENSOR_3V3AUX_SDA_R
J 0
(665 2810);
DISPLAY 0.510638 (665 2810);
PAINT WHITE (665 2810);
WIRE 16 -1 (600 2750)(1600 2750);
FORCEPROP 0 LAST CDS_PHYS_NET_NAME SMB_VR_SENSOR_3V3AUX_SCL_R
J 0
(640 2798);
PAINT MONO (640 2798);
DISPLAY INVISIBLE (640 2798);
FORCEPROP 2 LAST SIG_NAME SMB_VR_SENSOR_3V3AUX_SCL_R
J 0
(665 2760);
DISPLAY 0.510638 (665 2760);
PAINT WHITE (665 2760);
WIRE 16 -1 (-775 2750)(-100 2750);
FORCEPROP 0 LAST CDS_PHYS_NET_NAME PCA9548_PCIE0_ADDR2
J 0
(-735 2798);
PAINT MONO (-735 2798);
DISPLAY INVISIBLE (-735 2798);
FORCEPROP 2 LAST SIG_NAME PCA9548_PCIE0_ADDR2
J 0
(-735 2760);
DISPLAY 0.510638 (-735 2760);
PAINT WHITE (-735 2760);
WIRE 16 -1 (-1175 2200)(-2225 2200);
FORCEPROP 0 LAST CDS_PHYS_NET_NAME SMB_LM75_2_3V3AUX_SCL
J 0
(-3385 2248);
PAINT MONO (-3385 2248);
DISPLAY INVISIBLE (-3385 2248);
FORCEPROP 2 LAST SIG_NAME SMB_LM75_2_3V3AUX_SCL
J 0
(-1885 2210);
DISPLAY 0.510638 (-1885 2210);
PAINT WHITE (-1885 2210);
WIRE 16 -1 (-1175 2250)(-2225 2250);
FORCEPROP 0 LAST CDS_PHYS_NET_NAME SMB_LM75_2_3V3AUX_SDA
J 0
(-3385 2298);
PAINT MONO (-3385 2298);
DISPLAY INVISIBLE (-3385 2298);
FORCEPROP 2 LAST SIG_NAME SMB_LM75_2_3V3AUX_SDA
J 0
(-1885 2260);
DISPLAY 0.510638 (-1885 2260);
PAINT WHITE (-1885 2260);
WIRE 16 -1 (-1175 2300)(-2225 2300);
FORCEPROP 0 LAST CDS_PHYS_NET_NAME SMB_LM75_1_3V3AUX_SCL
J 0
(-3385 2348);
PAINT MONO (-3385 2348);
DISPLAY INVISIBLE (-3385 2348);
FORCEPROP 2 LAST SIG_NAME SMB_LM75_1_3V3AUX_SCL
J 0
(-1885 2310);
DISPLAY 0.510638 (-1885 2310);
PAINT WHITE (-1885 2310);
WIRE 16 -1 (-1175 2350)(-2225 2350);
FORCEPROP 0 LAST CDS_PHYS_NET_NAME SMB_LM75_1_3V3AUX_SDA
J 0
(-3385 2398);
PAINT MONO (-3385 2398);
DISPLAY INVISIBLE (-3385 2398);
FORCEPROP 2 LAST SIG_NAME SMB_LM75_1_3V3AUX_SDA
J 0
(-1885 2360);
DISPLAY 0.510638 (-1885 2360);
PAINT WHITE (-1885 2360);
WIRE 16 -1 (-2225 2400)(-1175 2400);
FORCEPROP 0 LAST CDS_PHYS_NET_NAME SMB_LM75_0_3V3AUX_SCL
J 0
(-2185 2448);
PAINT MONO (-2185 2448);
DISPLAY INVISIBLE (-2185 2448);
FORCEPROP 2 LAST SIG_NAME SMB_LM75_0_3V3AUX_SCL
J 0
(-1885 2410);
DISPLAY 0.510638 (-1885 2410);
PAINT WHITE (-1885 2410);
WIRE 16 -1 (-2225 2450)(-1175 2450);
FORCEPROP 0 LAST CDS_PHYS_NET_NAME SMB_LM75_0_3V3AUX_SDA
J 0
(-2185 2498);
PAINT MONO (-2185 2498);
DISPLAY INVISIBLE (-2185 2498);
FORCEPROP 2 LAST SIG_NAME SMB_LM75_0_3V3AUX_SDA
J 0
(-1885 2460);
DISPLAY 0.510638 (-1885 2460);
PAINT WHITE (-1885 2460);
WIRE 16 -1 (600 2550)(1475 2550);
FORCEPROP 0 LAST CDS_PHYS_NET_NAME SMB_LM75_3_3V3AUX_SDA_R
J 0
(640 2598);
PAINT MONO (640 2598);
DISPLAY INVISIBLE (640 2598);
FORCEPROP 2 LAST SIG_NAME SMB_LM75_3_3V3AUX_SDA_R
J 0
(715 2560);
DISPLAY 0.510638 (715 2560);
PAINT WHITE (715 2560);
WIRE 16 -1 (-775 2800)(-100 2800);
FORCEPROP 2 LAST SIG_NAME PCA9548_PCIE0_ADDR1
J 0
(-735 2810);
DISPLAY 0.510638 (-735 2810);
PAINT WHITE (-735 2810);
WIRE 16 -1 (3300 375)(2050 375);
FORCEPROP 0 LAST CDS_PHYS_NET_NAME SMB_IOEXP_3V3AUX_SDA
J 0
(2265 423);
PAINT MONO (2265 423);
DISPLAY INVISIBLE (2265 423);
FORCEPROP 2 LAST SIG_NAME SMB_LM75_1_3V3AUX_SDA
J 0
(2565 385);
DISPLAY 0.510638 (2565 385);
PAINT WHITE (2565 385);
WIRE 16 -1 (2075 125)(3325 125);
FORCEPROP 0 LAST CDS_PHYS_NET_NAME SMB_SENSOR_M2_P1_3V3AUX_SCL
J 0
(2115 173);
PAINT MONO (2115 173);
DISPLAY INVISIBLE (2115 173);
FORCEPROP 2 LAST SIG_NAME SMB_LM75_2_3V3AUX_SCL
J 0
(2590 135);
DISPLAY 0.510638 (2590 135);
PAINT WHITE (2590 135);
WIRE 16 -1 (2075 75)(3325 75);
FORCEPROP 0 LAST CDS_PHYS_NET_NAME SMB_SENSOR_M2_P1_3V3AUX_SDA
J 0
(2115 123);
PAINT MONO (2115 123);
DISPLAY INVISIBLE (2115 123);
FORCEPROP 2 LAST SIG_NAME SMB_LM75_2_3V3AUX_SDA
J 0
(2590 85);
DISPLAY 0.510638 (2590 85);
PAINT WHITE (2590 85);
WIRE 16 -1 (3300 425)(2050 425);
FORCEPROP 0 LAST CDS_PHYS_NET_NAME SMB_IOEXP_3V3AUX_SCL
J 0
(2265 473);
PAINT MONO (2265 473);
DISPLAY INVISIBLE (2265 473);
FORCEPROP 2 LAST SIG_NAME SMB_LM75_1_3V3AUX_SCL
J 0
(2565 435);
DISPLAY 0.510638 (2565 435);
PAINT WHITE (2565 435);
WIRE 16 -1 (3300 1075)(2050 1075);
FORCEPROP 0 LAST CDS_PHYS_NET_NAME SMB_PCIE0_3V3AUX_SCL
J 0
(2265 1123);
PAINT MONO (2265 1123);
DISPLAY INVISIBLE (2265 1123);
FORCEPROP 2 LAST SIG_NAME SMB_VR_3V3AUX_SCL
J 0
(2565 1085);
DISPLAY 0.510638 (2565 1085);
PAINT WHITE (2565 1085);
WIRE 16 -1 (3300 650)(2050 650);
FORCEPROP 0 LAST CDS_PHYS_NET_NAME SMB_INA230_3V3AUX_SDA
J 0
(2265 698);
PAINT MONO (2265 698);
DISPLAY INVISIBLE (2265 698);
FORCEPROP 2 LAST SIG_NAME SMB_LM75_0_3V3AUX_SDA
J 0
(2565 660);
DISPLAY 0.510638 (2565 660);
PAINT WHITE (2565 660);
WIRE 16 -1 (3300 1025)(2050 1025);
FORCEPROP 0 LAST CDS_PHYS_NET_NAME SMB_PCIE0_3V3AUX_SDA
J 0
(2265 1073);
PAINT MONO (2265 1073);
DISPLAY INVISIBLE (2265 1073);
FORCEPROP 2 LAST SIG_NAME SMB_VR_3V3AUX_SDA
J 0
(2565 1035);
DISPLAY 0.510638 (2565 1035);
PAINT WHITE (2565 1035);
WIRE 16 -1 (3300 700)(2050 700);
FORCEPROP 0 LAST CDS_PHYS_NET_NAME SMB_INA230_3V3AUX_SCL
J 0
(2265 748);
PAINT MONO (2265 748);
DISPLAY INVISIBLE (2265 748);
FORCEPROP 2 LAST SIG_NAME SMB_LM75_0_3V3AUX_SCL
J 0
(2565 710);
DISPLAY 0.510638 (2565 710);
PAINT WHITE (2565 710);
WIRE 16 -1 (-2600 300)(-2600 175);
WIRE 16 -1 (-2600 625)(-2600 300);
WIRE 16 -1 (-2600 300)(-1525 300);
FORCEPROP 2 LAST SIG_NAME PCA9548_PCIE0_ADDR0
J 0
(-2410 310);
DISPLAY 0.808511 (-2410 310);
PAINT WHITE (-2410 310);
WIRE 16 -1 (-2875 375)(-2875 175);
WIRE 16 -1 (-2875 625)(-2875 375);
WIRE 16 -1 (-2875 375)(-1525 375);
FORCEPROP 2 LAST SIG_NAME PCA9548_PCIE0_ADDR1
J 0
(-2410 385);
DISPLAY 0.808511 (-2410 385);
PAINT WHITE (-2410 385);
WIRE 16 -1 (-3150 450)(-3150 175);
WIRE 16 -1 (-3150 625)(-3150 450);
WIRE 16 -1 (-3150 450)(-1525 450);
FORCEPROP 2 LAST SIG_NAME PCA9548_PCIE0_ADDR2
J 0
(-2410 460);
DISPLAY 0.808511 (-2410 460);
PAINT WHITE (-2410 460);
DOT 1 (-2425 2650);
DOT 1 (-625 3475);
DOT 1 (1525 -425);
DOT 1 (1525 1025);
DOT 1 (-3150 450);
DOT 1 (-3150 975);
DOT 1 (-2600 300);
DOT 1 (-2875 375);
DOT 1 (-2875 975);
DOT 1 (1525 -175);
DOT 1 (1525 75);
DOT 1 (1525 375);
DOT 1 (1525 650);
DOT 1 (1525 700);
DOT 1 (1525 1075);
DOT 1 (1525 -225);
DOT 1 (1525 125);
DOT 1 (1525 425);
FORCENOTE
20211201 ADD R4269,R4270 
(1775 -675) 0;
DISPLAY LEFT (1775 -675);
DISPLAY 1.063830 (1775 -675);
PAINT WHITE (1775 -675);
FORCENOTE
20210929 MODIFY FOR GT
(-4450 4225) 0;
DISPLAY LEFT (-4450 4225);
DISPLAY 2.510638 (-4450 4225);
PAINT PINK (-4450 4225);
FORCENOTE
PCA9546 ADDR: 0XE0
(-3525 -400) 0;
DISPLAY LEFT (-3525 -400);
DISPLAY 1.595745 (-3525 -400);
PAINT SKYBLUE (-3525 -400);
QUIT
